FILE_TYPE = MACRO_DRAWING;
SET COLOR_WIRE YELLOW;
SET COLOR_PROP ORANGE;
SET COLOR_DOT WHITE;
SET COLOR_ARC YELLOW;
SET COLOR_BODY GREEN;
SET COLOR_NOTE PURPLE;
SET PROP_DISPLAY VALUE;
SET PAGE_NUMBER P150;
FORCEADD OFFPAGE..1
(-7625 5650);
FORCEPROP 2 LAST $XR0 149 
J 0
(-7877 5650);
DISPLAY 0.638298 (-7877 5650);
PAINT MONO (-7877 5650);
FORCEPROP 2 LAST CDS_LIB standard
J 2
(-7625 5650);
DISPLAY INVISIBLE (-7625 5650);
FORCEPROP 1 LAST OFFPAGE TRUE
J 0
(-7300 5525);
DISPLAY 0.872340 (-7300 5525);
PAINT GREEN (-7300 5525);
DISPLAY INVISIBLE (-7300 5525);
FORCEPROP 1 LAST COMMENT_BODY TRUE
J 0
(-7500 5550);
DISPLAY 0.872340 (-7500 5550);
PAINT GREEN (-7500 5550);
DISPLAY INVISIBLE (-7500 5550);
FORCEPROP 2 LAST PATH I10
J 2
(-7800 5725);
DISPLAY 1.021277 (-7800 5725);
DISPLAY INVISIBLE (-7800 5725);
FORCEADD OFFPAGE..1
(-7625 5550);
FORCEPROP 2 LAST $XR0 149 
J 0
(-7877 5550);
DISPLAY 0.638298 (-7877 5550);
PAINT MONO (-7877 5550);
FORCEPROP 2 LAST CDS_LIB standard
J 0
(-7625 5550);
DISPLAY INVISIBLE (-7625 5550);
FORCEPROP 1 LAST OFFPAGE TRUE
J 0
(-7300 5425);
DISPLAY 0.872340 (-7300 5425);
PAINT GREEN (-7300 5425);
DISPLAY INVISIBLE (-7300 5425);
FORCEPROP 1 LAST COMMENT_BODY TRUE
J 0
(-7500 5450);
DISPLAY 0.872340 (-7500 5450);
PAINT GREEN (-7500 5450);
DISPLAY INVISIBLE (-7500 5450);
FORCEPROP 2 LAST PATH I11
J 0
(-7575 5625);
DISPLAY 1.021277 (-7575 5625);
DISPLAY INVISIBLE (-7575 5625);
FORCEADD OFFPAGE..1
(-7625 5600);
FORCEPROP 2 LAST $XR0 149 
J 0
(-7877 5600);
DISPLAY 0.638298 (-7877 5600);
PAINT MONO (-7877 5600);
FORCEPROP 2 LAST CDS_LIB standard
J 0
(-7625 5600);
DISPLAY INVISIBLE (-7625 5600);
FORCEPROP 1 LAST OFFPAGE TRUE
J 0
(-7300 5475);
DISPLAY 0.872340 (-7300 5475);
PAINT GREEN (-7300 5475);
DISPLAY INVISIBLE (-7300 5475);
FORCEPROP 1 LAST COMMENT_BODY TRUE
J 0
(-7500 5500);
DISPLAY 0.872340 (-7500 5500);
PAINT GREEN (-7500 5500);
DISPLAY INVISIBLE (-7500 5500);
FORCEPROP 2 LAST PATH I12
J 0
(-7575 5675);
DISPLAY 1.021277 (-7575 5675);
DISPLAY INVISIBLE (-7575 5675);
FORCEADD GND..1
(-4650 5875);
FORCEPROP 3 LASTPIN (-4650 5925) SIG_NAME GND\g
J 0
(-4640 5935);
DISPLAY 0.659574 (-4640 5935);
PAINT MONO (-4640 5935);
DISPLAY INVISIBLE (-4640 5935);
FORCEPROP 2 LAST CDS_LIB pure_quanta_power
J 0
(-4650 5875);
DISPLAY INVISIBLE (-4650 5875);
FORCEPROP 1 LAST SIZE 1B
J 0
(-4575 5825);
DISPLAY 0.872340 (-4575 5825);
PAINT GREEN (-4575 5825);
DISPLAY INVISIBLE (-4575 5825);
FORCEPROP 1 LAST PATH I13
J 0
(-4575 5875);
DISPLAY 0.872340 (-4575 5875);
PAINT AQUA (-4575 5875);
DISPLAY INVISIBLE (-4575 5875);
FORCEPROP 1 LAST HDL_POWER GND
J 0
(-4650 6025);
DISPLAY 0.872340 (-4650 6025);
PAINT GREEN (-4650 6025);
DISPLAY INVISIBLE (-4650 6025);
FORCEADD Q_CAP..1
(-4650 6100);
FORCEPROP 1 LAST LOCATION C1516
J 0
(-4550 6250);
DISPLAY 0.489362 (-4550 6250);
PAINT SKYBLUE (-4550 6250);
FORCEPROP 2 LAST $SEC 1
J 0
(-4600 6300);
PAINT MONO (-4600 6300);
DISPLAY INVISIBLE (-4600 6300);
FORCEPROP 2 LAST CDS_SEC 1
J 0
(-4600 6300);
PAINT MONO (-4600 6300);
DISPLAY INVISIBLE (-4600 6300);
FORCEPROP 1 LASTPIN (-4650 6200) $PN 1
J 0
(-4640 6180);
DISPLAY 0.489362 (-4640 6180);
PAINT GREEN (-4640 6180);
FORCEPROP 1 LASTPIN (-4650 6000) $PN 2
J 0
(-4640 5980);
DISPLAY 0.489362 (-4640 5980);
PAINT GREEN (-4640 5980);
FORCEPROP 1 LAST MATERIAL X7R
J 0
(-4550 6050);
DISPLAY 0.489362 (-4550 6050);
PAINT SKYBLUE (-4550 6050);
FORCEPROP 1 LAST TOLERANCE 10%
J 0
(-4550 6100);
DISPLAY 0.489362 (-4550 6100);
PAINT SKYBLUE (-4550 6100);
FORCEPROP 1 LAST VALUE 0.1UF
J 0
(-4550 6200);
DISPLAY 0.489362 (-4550 6200);
PAINT SKYBLUE (-4550 6200);
FORCEPROP 1 LAST PART_NUMBER CH4103K1B08
J 0
(-4550 6000);
DISPLAY 0.489362 (-4550 6000);
PAINT SKYBLUE (-4550 6000);
FORCEPROP 1 LAST VOLTAGE 16V
J 0
(-4550 6150);
DISPLAY 0.489362 (-4550 6150);
PAINT SKYBLUE (-4550 6150);
FORCEPROP 1 LAST PACK_TYPE C0402
J 0
(-4550 5950);
DISPLAY 0.489362 (-4550 5950);
PAINT SKYBLUE (-4550 5950);
FORCEPROP 2 LAST CDS_LIB pure_quanta
J 0
(-4650 6100);
DISPLAY INVISIBLE (-4650 6100);
FORCEPROP 1 LAST PATH I14
J 0
(-4600 6250);
DISPLAY 0.978723 (-4600 6250);
PAINT WHITE (-4600 6250);
DISPLAY INVISIBLE (-4600 6250);
FORCEADD UNIVERSAL_POWER..1
(-4800 6425);
FORCEPROP 3 LASTPIN (-4800 6375) SIG_NAME PVDD18_S5_P0\g
J 0
(-4790 6385);
DISPLAY 0.659574 (-4790 6385);
PAINT MONO (-4790 6385);
DISPLAY INVISIBLE (-4790 6385);
FORCEPROP 1 LAST HDL_POWER PVDD18_S5_P0
J 1
(-4800 6475);
DISPLAY 0.489362 (-4800 6475);
PAINT GREEN (-4800 6475);
FORCEPROP 2 LAST CDS_LIB pure_quanta_power
J 0
(-4800 6425);
PAINT MONO (-4800 6425);
DISPLAY INVISIBLE (-4800 6425);
FORCEPROP 1 LAST PATH I15
J 0
(-4750 6450);
DISPLAY 0.872340 (-4750 6450);
PAINT AQUA (-4750 6450);
DISPLAY INVISIBLE (-4750 6450);
FORCEADD GND..1
(-4800 4975);
FORCEPROP 3 LASTPIN (-4800 5025) SIG_NAME GND\g
J 0
(-4790 5035);
DISPLAY 0.659574 (-4790 5035);
PAINT MONO (-4790 5035);
DISPLAY INVISIBLE (-4790 5035);
FORCEPROP 1 LAST SIZE 1B
J 0
(-4725 4925);
DISPLAY 0.872340 (-4725 4925);
PAINT GREEN (-4725 4925);
DISPLAY INVISIBLE (-4725 4925);
FORCEPROP 2 LAST CDS_LIB pure_quanta_power
J 0
(-4800 4975);
PAINT MONO (-4800 4975);
DISPLAY INVISIBLE (-4800 4975);
FORCEPROP 1 LAST PATH I16
J 0
(-4725 4975);
DISPLAY 0.872340 (-4725 4975);
PAINT AQUA (-4725 4975);
DISPLAY INVISIBLE (-4725 4975);
FORCEPROP 1 LAST HDL_POWER GND
J 0
(-4800 5125);
DISPLAY 0.872340 (-4800 5125);
PAINT GREEN (-4800 5125);
DISPLAY INVISIBLE (-4800 5125);
FORCEADD GND..1
(-6050 5925);
FORCEPROP 3 LASTPIN (-6050 5975) SIG_NAME GND\g
J 0
(-6040 5985);
DISPLAY 0.659574 (-6040 5985);
PAINT MONO (-6040 5985);
DISPLAY INVISIBLE (-6040 5985);
FORCEPROP 1 LAST SIZE 1B
J 0
(-5975 5875);
DISPLAY 0.872340 (-5975 5875);
PAINT GREEN (-5975 5875);
DISPLAY INVISIBLE (-5975 5875);
FORCEPROP 2 LAST CDS_LIB pure_quanta_power
J 0
(-6050 5925);
DISPLAY INVISIBLE (-6050 5925);
FORCEPROP 1 LAST PATH I17
J 0
(-5975 5925);
DISPLAY 0.872340 (-5975 5925);
PAINT AQUA (-5975 5925);
DISPLAY INVISIBLE (-5975 5925);
FORCEPROP 1 LAST HDL_POWER GND
J 0
(-6050 6075);
DISPLAY 0.872340 (-6050 6075);
PAINT GREEN (-6050 6075);
DISPLAY INVISIBLE (-6050 6075);
FORCEADD UNIVERSAL_POWER..1
(-5850 6425);
FORCEPROP 3 LASTPIN (-5850 6375) SIG_NAME PVDD18_S5_P0\g
J 0
(-5840 6385);
DISPLAY 0.659574 (-5840 6385);
PAINT MONO (-5840 6385);
DISPLAY INVISIBLE (-5840 6385);
FORCEPROP 1 LAST HDL_POWER PVDD18_S5_P0
J 1
(-5850 6475);
DISPLAY 0.489362 (-5850 6475);
PAINT GREEN (-5850 6475);
FORCEPROP 2 LAST CDS_LIB pure_quanta_power
J 0
(-5850 6425);
PAINT MONO (-5850 6425);
DISPLAY INVISIBLE (-5850 6425);
FORCEPROP 1 LAST PATH I18
J 0
(-5800 6450);
DISPLAY 0.872340 (-5800 6450);
PAINT AQUA (-5800 6450);
DISPLAY INVISIBLE (-5800 6450);
FORCEADD Q_CAP..1
(-6050 6100);
FORCEPROP 1 LAST LOCATION C1514
J 0
(-6200 6225);
DISPLAY 0.489362 (-6200 6225);
PAINT SKYBLUE (-6200 6225);
FORCEPROP 2 LAST $SEC 1
J 0
(-6000 6300);
PAINT MONO (-6000 6300);
DISPLAY INVISIBLE (-6000 6300);
FORCEPROP 2 LAST CDS_SEC 1
J 0
(-6000 6300);
PAINT MONO (-6000 6300);
DISPLAY INVISIBLE (-6000 6300);
FORCEPROP 1 LASTPIN (-6050 6200) $PN 1
J 0
(-6040 6180);
DISPLAY 0.489362 (-6040 6180);
PAINT GREEN (-6040 6180);
FORCEPROP 1 LASTPIN (-6050 6000) $PN 2
J 0
(-6040 5980);
DISPLAY 0.489362 (-6040 5980);
PAINT GREEN (-6040 5980);
FORCEPROP 1 LAST MATERIAL X7R
J 0
(-6175 6025);
DISPLAY 0.489362 (-6175 6025);
PAINT SKYBLUE (-6175 6025);
FORCEPROP 1 LAST TOLERANCE 10%
J 0
(-6175 6075);
DISPLAY 0.489362 (-6175 6075);
PAINT SKYBLUE (-6175 6075);
FORCEPROP 1 LAST VALUE 0.1UF
J 0
(-6225 6175);
DISPLAY 0.489362 (-6225 6175);
PAINT SKYBLUE (-6225 6175);
FORCEPROP 1 LAST PART_NUMBER CH4103K1B08
J 0
(-6400 5975);
DISPLAY 0.489362 (-6400 5975);
PAINT SKYBLUE (-6400 5975);
FORCEPROP 1 LAST VOLTAGE 16V
J 0
(-6175 6125);
DISPLAY 0.489362 (-6175 6125);
PAINT SKYBLUE (-6175 6125);
FORCEPROP 1 LAST PACK_TYPE C0402
J 0
(-6225 5925);
DISPLAY 0.489362 (-6225 5925);
PAINT SKYBLUE (-6225 5925);
FORCEPROP 2 LAST CDS_LIB pure_quanta
J 0
(-6050 6100);
DISPLAY INVISIBLE (-6050 6100);
FORCEPROP 1 LAST PATH I19
J 0
(-6000 6250);
DISPLAY 0.978723 (-6000 6250);
PAINT WHITE (-6000 6250);
DISPLAY INVISIBLE (-6000 6250);
FORCEADD OFFPAGE..2
(-2375 5700);
FORCEPROP 2 LAST $XR0 27 
J 0
(-2186 5700);
DISPLAY 0.638298 (-2186 5700);
PAINT MONO (-2186 5700);
FORCEPROP 2 LAST CDS_LIB standard
J 0
(-2375 5700);
PAINT MONO (-2375 5700);
DISPLAY INVISIBLE (-2375 5700);
FORCEPROP 1 LAST OFFPAGE TRUE
J 0
(-2050 5575);
DISPLAY 0.872340 (-2050 5575);
PAINT GREEN (-2050 5575);
DISPLAY INVISIBLE (-2050 5575);
FORCEPROP 1 LAST COMMENT_BODY TRUE
J 0
(-2420 5605);
DISPLAY 0.872340 (-2420 5605);
PAINT GREEN (-2420 5605);
DISPLAY INVISIBLE (-2420 5605);
FORCEPROP 2 LAST PATH I20
J 0
(-2175 5750);
DISPLAY 1.021277 (-2175 5750);
DISPLAY INVISIBLE (-2175 5750);
FORCEADD OFFPAGE..2
(-2375 5550);
FORCEPROP 2 LAST $XR0 27 
J 0
(-2186 5550);
DISPLAY 0.638298 (-2186 5550);
PAINT MONO (-2186 5550);
FORCEPROP 2 LAST CDS_LIB standard
J 0
(-2375 5550);
PAINT MONO (-2375 5550);
DISPLAY INVISIBLE (-2375 5550);
FORCEPROP 1 LAST OFFPAGE TRUE
J 0
(-2050 5425);
DISPLAY 0.872340 (-2050 5425);
PAINT GREEN (-2050 5425);
DISPLAY INVISIBLE (-2050 5425);
FORCEPROP 1 LAST COMMENT_BODY TRUE
J 0
(-2420 5455);
DISPLAY 0.872340 (-2420 5455);
PAINT GREEN (-2420 5455);
DISPLAY INVISIBLE (-2420 5455);
FORCEPROP 2 LAST PATH I21
J 0
(-2175 5600);
DISPLAY 1.021277 (-2175 5600);
DISPLAY INVISIBLE (-2175 5600);
FORCEADD OFFPAGE..2
(-2375 5600);
FORCEPROP 2 LAST $XR0 27 
J 0
(-2186 5600);
DISPLAY 0.638298 (-2186 5600);
PAINT MONO (-2186 5600);
FORCEPROP 2 LAST CDS_LIB standard
J 0
(-2375 5600);
PAINT MONO (-2375 5600);
DISPLAY INVISIBLE (-2375 5600);
FORCEPROP 1 LAST OFFPAGE TRUE
J 0
(-2050 5475);
DISPLAY 0.872340 (-2050 5475);
PAINT GREEN (-2050 5475);
DISPLAY INVISIBLE (-2050 5475);
FORCEPROP 1 LAST COMMENT_BODY TRUE
J 0
(-2420 5505);
DISPLAY 0.872340 (-2420 5505);
PAINT GREEN (-2420 5505);
DISPLAY INVISIBLE (-2420 5505);
FORCEPROP 2 LAST PATH I22
J 0
(-2175 5650);
DISPLAY 1.021277 (-2175 5650);
DISPLAY INVISIBLE (-2175 5650);
FORCEADD OFFPAGE..2
(-2375 5650);
FORCEPROP 2 LAST $XR0 27 
J 0
(-2186 5650);
DISPLAY 0.638298 (-2186 5650);
PAINT MONO (-2186 5650);
FORCEPROP 2 LAST CDS_LIB standard
J 0
(-2375 5650);
PAINT MONO (-2375 5650);
DISPLAY INVISIBLE (-2375 5650);
FORCEPROP 1 LAST OFFPAGE TRUE
J 0
(-2050 5525);
DISPLAY 0.872340 (-2050 5525);
PAINT GREEN (-2050 5525);
DISPLAY INVISIBLE (-2050 5525);
FORCEPROP 1 LAST COMMENT_BODY TRUE
J 0
(-2420 5555);
DISPLAY 0.872340 (-2420 5555);
PAINT GREEN (-2420 5555);
DISPLAY INVISIBLE (-2420 5555);
FORCEPROP 2 LAST PATH I23
J 0
(-2175 5700);
DISPLAY 1.021277 (-2175 5700);
DISPLAY INVISIBLE (-2175 5700);
FORCEADD Q_RES..1
(-3625 5550);
FORCEPROP 1 LAST LOCATION R1641
J 0
(-4000 5550);
DISPLAY 0.489362 (-4000 5550);
PAINT SKYBLUE (-4000 5550);
FORCEPROP 0 LAST $SEC 1
J 0
(-3875 5600);
PAINT MONO (-3875 5600);
DISPLAY INVISIBLE (-3875 5600);
FORCEPROP 0 LAST CDS_SEC 1
J 0
(-3875 5600);
PAINT MONO (-3875 5600);
DISPLAY INVISIBLE (-3875 5600);
FORCEPROP 1 LASTPIN (-3725 5550) $PN 1
J 0
(-3713 5562);
DISPLAY 0.489362 (-3713 5562);
PAINT GREEN (-3713 5562);
FORCEPROP 1 LASTPIN (-3525 5550) $PN 2
J 0
(-3563 5562);
DISPLAY 0.489362 (-3563 5562);
PAINT GREEN (-3563 5562);
FORCEPROP 1 LAST MATERIAL CHIP
J 0
(-3800 5525);
DISPLAY 0.489362 (-3800 5525);
PAINT SKYBLUE (-3800 5525);
FORCEPROP 1 LAST TOLERANCE 1%
J 0
(-3525 5525);
DISPLAY 0.489362 (-3525 5525);
PAINT SKYBLUE (-3525 5525);
FORCEPROP 1 LAST VALUE 22
J 2
(-3725 5550);
DISPLAY 0.489362 (-3725 5550);
PAINT SKYBLUE (-3725 5550);
FORCEPROP 2 LAST CDS_LIB pure_quanta
J 0
(-3625 5550);
PAINT MONO (-3625 5550);
DISPLAY INVISIBLE (-3625 5550);
FORCEPROP 1 LAST PATH I24
J 0
(-3675 5700);
DISPLAY 0.978723 (-3675 5700);
PAINT WHITE (-3675 5700);
DISPLAY INVISIBLE (-3675 5700);
FORCEPROP 1 LAST WATTAGE 1/16W
J 2
(-3650 5400);
DISPLAY 0.978723 (-3650 5400);
PAINT SKYBLUE (-3650 5400);
DISPLAY INVISIBLE (-3650 5400);
FORCEPROP 1 LAST PART_NUMBER CS02202FB12
J 0
(-3675 5650);
DISPLAY 0.978723 (-3675 5650);
PAINT SKYBLUE (-3675 5650);
DISPLAY INVISIBLE (-3675 5650);
FORCEPROP 1 LAST PACK_TYPE 0402LF
J 0
(-3375 5400);
DISPLAY 0.978723 (-3375 5400);
PAINT SKYBLUE (-3375 5400);
DISPLAY INVISIBLE (-3375 5400);
FORCEADD Q_RES..1
(-3625 5650);
FORCEPROP 1 LAST LOCATION R1639
J 0
(-4000 5650);
DISPLAY 0.489362 (-4000 5650);
PAINT SKYBLUE (-4000 5650);
FORCEPROP 0 LAST $SEC 1
J 0
(-3950 5700);
DISPLAY 0.680851 (-3950 5700);
PAINT MONO (-3950 5700);
DISPLAY INVISIBLE (-3950 5700);
FORCEPROP 0 LAST CDS_SEC 1
J 0
(-3950 5700);
DISPLAY 1.021277 (-3950 5700);
DISPLAY INVISIBLE (-3950 5700);
FORCEPROP 1 LASTPIN (-3725 5650) $PN 1
J 0
(-3713 5662);
DISPLAY 0.489362 (-3713 5662);
PAINT MONO (-3713 5662);
FORCEPROP 1 LASTPIN (-3525 5650) $PN 2
J 0
(-3563 5662);
DISPLAY 0.489362 (-3563 5662);
PAINT MONO (-3563 5662);
FORCEPROP 1 LAST MATERIAL CHIP
J 0
(-3800 5625);
DISPLAY 0.489362 (-3800 5625);
PAINT SKYBLUE (-3800 5625);
FORCEPROP 1 LAST TOLERANCE 1%
J 0
(-3525 5625);
DISPLAY 0.489362 (-3525 5625);
PAINT SKYBLUE (-3525 5625);
FORCEPROP 1 LAST VALUE 22
J 2
(-3725 5650);
DISPLAY 0.489362 (-3725 5650);
PAINT SKYBLUE (-3725 5650);
FORCEPROP 2 LAST CDS_LIB pure_quanta
J 0
(-3625 5650);
DISPLAY INVISIBLE (-3625 5650);
FORCEPROP 1 LAST PATH I25
J 0
(-3675 5800);
DISPLAY 0.978723 (-3675 5800);
PAINT WHITE (-3675 5800);
DISPLAY INVISIBLE (-3675 5800);
FORCEPROP 1 LAST WATTAGE 1/16W
J 2
(-3650 5500);
DISPLAY 0.978723 (-3650 5500);
PAINT SKYBLUE (-3650 5500);
DISPLAY INVISIBLE (-3650 5500);
FORCEPROP 1 LAST PART_NUMBER CS02202FB12
J 0
(-3675 5750);
DISPLAY 0.978723 (-3675 5750);
PAINT SKYBLUE (-3675 5750);
DISPLAY INVISIBLE (-3675 5750);
FORCEPROP 1 LAST PACK_TYPE 0402LF
J 0
(-3375 5500);
DISPLAY 0.978723 (-3375 5500);
PAINT SKYBLUE (-3375 5500);
DISPLAY INVISIBLE (-3375 5500);
FORCEADD Q_RES..1
(-3625 5600);
FORCEPROP 1 LAST LOCATION R1640
J 0
(-4000 5600);
DISPLAY 0.489362 (-4000 5600);
PAINT SKYBLUE (-4000 5600);
FORCEPROP 0 LAST $SEC 1
J 0
(-3875 5650);
PAINT MONO (-3875 5650);
DISPLAY INVISIBLE (-3875 5650);
FORCEPROP 0 LAST CDS_SEC 1
J 0
(-3875 5650);
PAINT MONO (-3875 5650);
DISPLAY INVISIBLE (-3875 5650);
FORCEPROP 1 LASTPIN (-3725 5600) $PN 1
J 0
(-3713 5612);
DISPLAY 0.489362 (-3713 5612);
PAINT GREEN (-3713 5612);
FORCEPROP 1 LASTPIN (-3525 5600) $PN 2
J 0
(-3563 5612);
DISPLAY 0.489362 (-3563 5612);
PAINT GREEN (-3563 5612);
FORCEPROP 1 LAST MATERIAL CHIP
J 0
(-3800 5575);
DISPLAY 0.489362 (-3800 5575);
PAINT SKYBLUE (-3800 5575);
FORCEPROP 1 LAST TOLERANCE 1%
J 0
(-3525 5575);
DISPLAY 0.489362 (-3525 5575);
PAINT SKYBLUE (-3525 5575);
FORCEPROP 1 LAST VALUE 22
J 2
(-3725 5600);
DISPLAY 0.489362 (-3725 5600);
PAINT SKYBLUE (-3725 5600);
FORCEPROP 2 LAST CDS_LIB pure_quanta
J 0
(-3625 5600);
PAINT MONO (-3625 5600);
DISPLAY INVISIBLE (-3625 5600);
FORCEPROP 1 LAST PATH I26
J 0
(-3675 5750);
DISPLAY 0.978723 (-3675 5750);
PAINT WHITE (-3675 5750);
DISPLAY INVISIBLE (-3675 5750);
FORCEPROP 1 LAST WATTAGE 1/16W
J 2
(-3650 5450);
DISPLAY 0.978723 (-3650 5450);
PAINT SKYBLUE (-3650 5450);
DISPLAY INVISIBLE (-3650 5450);
FORCEPROP 1 LAST PART_NUMBER CS02202FB12
J 0
(-3675 5700);
DISPLAY 0.978723 (-3675 5700);
PAINT SKYBLUE (-3675 5700);
DISPLAY INVISIBLE (-3675 5700);
FORCEPROP 1 LAST PACK_TYPE 0402LF
J 0
(-3375 5450);
DISPLAY 0.978723 (-3375 5450);
PAINT SKYBLUE (-3375 5450);
DISPLAY INVISIBLE (-3375 5450);
FORCEADD Q_RES..1
(-3625 5700);
FORCEPROP 1 LAST LOCATION R1638
J 0
(-4000 5700);
DISPLAY 0.489362 (-4000 5700);
PAINT SKYBLUE (-4000 5700);
FORCEPROP 0 LAST $SEC 1
J 0
(-3875 5750);
PAINT MONO (-3875 5750);
DISPLAY INVISIBLE (-3875 5750);
FORCEPROP 0 LAST CDS_SEC 1
J 0
(-3875 5750);
PAINT MONO (-3875 5750);
DISPLAY INVISIBLE (-3875 5750);
FORCEPROP 1 LASTPIN (-3725 5700) $PN 1
J 0
(-3713 5712);
DISPLAY 0.489362 (-3713 5712);
PAINT GREEN (-3713 5712);
FORCEPROP 1 LASTPIN (-3525 5700) $PN 2
J 0
(-3563 5712);
DISPLAY 0.489362 (-3563 5712);
PAINT GREEN (-3563 5712);
FORCEPROP 1 LAST MATERIAL CHIP
J 0
(-3800 5675);
DISPLAY 0.489362 (-3800 5675);
PAINT SKYBLUE (-3800 5675);
FORCEPROP 1 LAST TOLERANCE 1%
J 0
(-3525 5675);
DISPLAY 0.489362 (-3525 5675);
PAINT SKYBLUE (-3525 5675);
FORCEPROP 1 LAST VALUE 22
J 2
(-3725 5700);
DISPLAY 0.489362 (-3725 5700);
PAINT SKYBLUE (-3725 5700);
FORCEPROP 2 LAST CDS_LIB pure_quanta
J 0
(-3625 5700);
PAINT MONO (-3625 5700);
DISPLAY INVISIBLE (-3625 5700);
FORCEPROP 1 LAST PATH I27
J 0
(-3675 5850);
DISPLAY 0.978723 (-3675 5850);
PAINT WHITE (-3675 5850);
DISPLAY INVISIBLE (-3675 5850);
FORCEPROP 1 LAST WATTAGE 1/16W
J 2
(-3650 5550);
DISPLAY 0.978723 (-3650 5550);
PAINT SKYBLUE (-3650 5550);
DISPLAY INVISIBLE (-3650 5550);
FORCEPROP 1 LAST PART_NUMBER CS02202FB12
J 0
(-3675 5800);
DISPLAY 0.978723 (-3675 5800);
PAINT SKYBLUE (-3675 5800);
DISPLAY INVISIBLE (-3675 5800);
FORCEPROP 1 LAST PACK_TYPE 0402LF
J 0
(-3375 5550);
DISPLAY 0.978723 (-3375 5550);
PAINT SKYBLUE (-3375 5550);
DISPLAY INVISIBLE (-3375 5550);
FORCEADD SN74AVC4T774PWR..1
(-5325 3875);
FORCEPROP 1 LAST LOCATION U151
J 0
(-5572 4440);
DISPLAY 0.489362 (-5572 4440);
PAINT SKYBLUE (-5572 4440);
FORCEPROP 0 LAST $SEC 1
J 0
(-5575 4625);
DISPLAY 0.680851 (-5575 4625);
PAINT MONO (-5575 4625);
DISPLAY INVISIBLE (-5575 4625);
FORCEPROP 0 LAST CDS_SEC 1
J 0
(-5575 4625);
DISPLAY 1.021277 (-5575 4625);
DISPLAY INVISIBLE (-5575 4625);
FORCEPROP 0 LASTPIN (-5725 4025) $PN 3
J 2
(-5735 4035);
DISPLAY 0.489362 (-5735 4035);
PAINT MONO (-5735 4035);
FORCEPROP 0 LASTPIN (-5725 3975) $PN 4
J 2
(-5735 3985);
DISPLAY 0.489362 (-5735 3985);
PAINT MONO (-5735 3985);
FORCEPROP 0 LASTPIN (-5725 3925) $PN 5
J 2
(-5735 3935);
DISPLAY 0.489362 (-5735 3935);
PAINT MONO (-5735 3935);
FORCEPROP 0 LASTPIN (-5725 3875) $PN 6
J 2
(-5735 3885);
DISPLAY 0.489362 (-5735 3885);
PAINT MONO (-5735 3885);
FORCEPROP 0 LASTPIN (-4925 4025) $PN 14
J 0
(-4915 4035);
DISPLAY 0.489362 (-4915 4035);
PAINT MONO (-4915 4035);
FORCEPROP 0 LASTPIN (-4925 3975) $PN 13
J 0
(-4915 3985);
DISPLAY 0.489362 (-4915 3985);
PAINT MONO (-4915 3985);
FORCEPROP 0 LASTPIN (-4925 3925) $PN 12
J 0
(-4915 3935);
DISPLAY 0.489362 (-4915 3935);
PAINT MONO (-4915 3935);
FORCEPROP 0 LASTPIN (-4925 3875) $PN 11
J 0
(-4915 3885);
DISPLAY 0.489362 (-4915 3885);
PAINT MONO (-4915 3885);
FORCEPROP 0 LASTPIN (-5725 3725) $PN 1
J 2
(-5735 3735);
DISPLAY 0.489362 (-5735 3735);
PAINT MONO (-5735 3735);
FORCEPROP 0 LASTPIN (-5725 3675) $PN 2
J 2
(-5735 3685);
DISPLAY 0.489362 (-5735 3685);
PAINT MONO (-5735 3685);
FORCEPROP 0 LASTPIN (-5725 3625) $PN 7
J 2
(-5735 3635);
DISPLAY 0.489362 (-5735 3635);
PAINT MONO (-5735 3635);
FORCEPROP 0 LASTPIN (-5725 3575) $PN 8
J 2
(-5735 3585);
DISPLAY 0.489362 (-5735 3585);
PAINT MONO (-5735 3585);
FORCEPROP 0 LASTPIN (-4925 3475) $PN 10
J 0
(-4915 3485);
DISPLAY 0.489362 (-4915 3485);
PAINT MONO (-4915 3485);
FORCEPROP 0 LASTPIN (-5725 3525) $PN 9
J 2
(-5735 3535);
DISPLAY 0.489362 (-5735 3535);
PAINT MONO (-5735 3535);
FORCEPROP 0 LASTPIN (-5725 4225) $PN 16
J 2
(-5735 4235);
DISPLAY 0.489362 (-5735 4235);
PAINT MONO (-5735 4235);
FORCEPROP 0 LASTPIN (-4925 4225) $PN 15
J 0
(-4915 4235);
DISPLAY 0.489362 (-4915 4235);
PAINT MONO (-4915 4235);
FORCEPROP 2 LAST PART_TYPE SMLF
J 0
(-5575 4575);
PAINT MONO (-5575 4575);
FORCEPROP 1 LAST MATERIAL IC
J 0
(-5572 4328);
DISPLAY 0.489362 (-5572 4328);
PAINT SKYBLUE (-5572 4328);
FORCEPROP 2 LAST VALUE SN74AVC4T774PWR
J 0
(-5575 4500);
DISPLAY 0.489362 (-5575 4500);
PAINT SKYBLUE (-5575 4500);
FORCEPROP 1 LAST PART_NUMBER AL04T774K00
J 0
(-5572 4383);
DISPLAY 0.489362 (-5572 4383);
PAINT SKYBLUE (-5572 4383);
FORCEPROP 1 LAST NEEDS_NO_SIZE TRUE
J 0
(-5325 3875);
DISPLAY 0.723404 (-5325 3875);
PAINT GREEN (-5325 3875);
DISPLAY INVISIBLE (-5325 3875);
FORCEPROP 1 LAST CDS_LMAN_SYM_OUTLINE -250,450,250,-450
J 0
(-5325 3875);
DISPLAY 0.468085 (-5325 3875);
PAINT GREEN (-5325 3875);
DISPLAY INVISIBLE (-5325 3875);
FORCEPROP 2 LAST CDS_LIB pure_quanta
J 0
(-5325 3875);
DISPLAY INVISIBLE (-5325 3875);
FORCEPROP 1 LAST PATH I28
J 0
(-5325 3875);
DISPLAY 0.723404 (-5325 3875);
PAINT GREEN (-5325 3875);
DISPLAY INVISIBLE (-5325 3875);
FORCEADD OFFPAGE..2
(-2325 3925);
FORCEPROP 2 LAST $XR0 54 
J 0
(-2136 3925);
DISPLAY 0.638298 (-2136 3925);
PAINT MONO (-2136 3925);
FORCEPROP 2 LAST CDS_LIB standard
J 0
(-2325 3925);
PAINT MONO (-2325 3925);
DISPLAY INVISIBLE (-2325 3925);
FORCEPROP 1 LAST OFFPAGE TRUE
J 0
(-2000 3800);
DISPLAY 0.872340 (-2000 3800);
PAINT GREEN (-2000 3800);
DISPLAY INVISIBLE (-2000 3800);
FORCEPROP 1 LAST COMMENT_BODY TRUE
J 0
(-2370 3830);
DISPLAY 0.872340 (-2370 3830);
PAINT GREEN (-2370 3830);
DISPLAY INVISIBLE (-2370 3830);
FORCEPROP 2 LAST PATH I29
J 0
(-2125 3975);
DISPLAY 1.021277 (-2125 3975);
DISPLAY INVISIBLE (-2125 3975);
FORCEADD OFFPAGE..2
(-2325 3975);
FORCEPROP 2 LAST $XR0 54 
J 0
(-2136 3975);
DISPLAY 0.638298 (-2136 3975);
PAINT MONO (-2136 3975);
FORCEPROP 2 LAST CDS_LIB standard
J 0
(-2325 3975);
PAINT MONO (-2325 3975);
DISPLAY INVISIBLE (-2325 3975);
FORCEPROP 1 LAST OFFPAGE TRUE
J 0
(-2000 3850);
DISPLAY 0.872340 (-2000 3850);
PAINT GREEN (-2000 3850);
DISPLAY INVISIBLE (-2000 3850);
FORCEPROP 1 LAST COMMENT_BODY TRUE
J 0
(-2370 3880);
DISPLAY 0.872340 (-2370 3880);
PAINT GREEN (-2370 3880);
DISPLAY INVISIBLE (-2370 3880);
FORCEPROP 2 LAST PATH I30
J 0
(-2125 4025);
DISPLAY 1.021277 (-2125 4025);
DISPLAY INVISIBLE (-2125 4025);
FORCEADD OFFPAGE..2
(-2325 4025);
FORCEPROP 2 LAST $XR0 54 
J 0
(-2136 4025);
DISPLAY 0.638298 (-2136 4025);
PAINT MONO (-2136 4025);
FORCEPROP 2 LAST CDS_LIB standard
J 0
(-2325 4025);
PAINT MONO (-2325 4025);
DISPLAY INVISIBLE (-2325 4025);
FORCEPROP 1 LAST OFFPAGE TRUE
J 0
(-2000 3900);
DISPLAY 0.872340 (-2000 3900);
PAINT GREEN (-2000 3900);
DISPLAY INVISIBLE (-2000 3900);
FORCEPROP 1 LAST COMMENT_BODY TRUE
J 0
(-2370 3930);
DISPLAY 0.872340 (-2370 3930);
PAINT GREEN (-2370 3930);
DISPLAY INVISIBLE (-2370 3930);
FORCEPROP 2 LAST PATH I31
J 0
(-2125 4075);
DISPLAY 1.021277 (-2125 4075);
DISPLAY INVISIBLE (-2125 4075);
FORCEADD OFFPAGE..2
(-2325 3875);
FORCEPROP 2 LAST $XR0 54 
J 0
(-2136 3875);
DISPLAY 0.638298 (-2136 3875);
PAINT MONO (-2136 3875);
FORCEPROP 2 LAST CDS_LIB standard
J 0
(-2325 3875);
PAINT MONO (-2325 3875);
DISPLAY INVISIBLE (-2325 3875);
FORCEPROP 1 LAST OFFPAGE TRUE
J 0
(-2000 3750);
DISPLAY 0.872340 (-2000 3750);
PAINT GREEN (-2000 3750);
DISPLAY INVISIBLE (-2000 3750);
FORCEPROP 1 LAST COMMENT_BODY TRUE
J 0
(-2370 3780);
DISPLAY 0.872340 (-2370 3780);
PAINT GREEN (-2370 3780);
DISPLAY INVISIBLE (-2370 3780);
FORCEPROP 2 LAST PATH I32
J 0
(-2125 3925);
DISPLAY 1.021277 (-2125 3925);
DISPLAY INVISIBLE (-2125 3925);
FORCEADD Q_RES..1
(-3625 4025);
FORCEPROP 1 LAST LOCATION R1642
J 0
(-4000 4025);
DISPLAY 0.489362 (-4000 4025);
PAINT SKYBLUE (-4000 4025);
FORCEPROP 0 LAST $SEC 1
J 0
(-3875 4075);
PAINT MONO (-3875 4075);
DISPLAY INVISIBLE (-3875 4075);
FORCEPROP 0 LAST CDS_SEC 1
J 0
(-3875 4075);
PAINT MONO (-3875 4075);
DISPLAY INVISIBLE (-3875 4075);
FORCEPROP 1 LASTPIN (-3725 4025) $PN 1
J 0
(-3713 4037);
DISPLAY 0.489362 (-3713 4037);
PAINT GREEN (-3713 4037);
FORCEPROP 1 LASTPIN (-3525 4025) $PN 2
J 0
(-3563 4037);
DISPLAY 0.489362 (-3563 4037);
PAINT GREEN (-3563 4037);
FORCEPROP 1 LAST MATERIAL CHIP
J 0
(-3800 4000);
DISPLAY 0.489362 (-3800 4000);
PAINT SKYBLUE (-3800 4000);
FORCEPROP 1 LAST TOLERANCE 1%
J 0
(-3525 4000);
DISPLAY 0.489362 (-3525 4000);
PAINT SKYBLUE (-3525 4000);
FORCEPROP 1 LAST VALUE 22
J 2
(-3725 4025);
DISPLAY 0.489362 (-3725 4025);
PAINT SKYBLUE (-3725 4025);
FORCEPROP 2 LAST CDS_LIB pure_quanta
J 0
(-3625 4025);
PAINT MONO (-3625 4025);
DISPLAY INVISIBLE (-3625 4025);
FORCEPROP 1 LAST PATH I33
J 0
(-3675 4175);
DISPLAY 0.978723 (-3675 4175);
PAINT WHITE (-3675 4175);
DISPLAY INVISIBLE (-3675 4175);
FORCEPROP 1 LAST WATTAGE 1/16W
J 2
(-3650 3875);
DISPLAY 0.978723 (-3650 3875);
PAINT SKYBLUE (-3650 3875);
DISPLAY INVISIBLE (-3650 3875);
FORCEPROP 1 LAST PART_NUMBER CS02202FB12
J 0
(-3675 4125);
DISPLAY 0.978723 (-3675 4125);
PAINT SKYBLUE (-3675 4125);
DISPLAY INVISIBLE (-3675 4125);
FORCEPROP 1 LAST PACK_TYPE 0402LF
J 0
(-3375 3875);
DISPLAY 0.978723 (-3375 3875);
PAINT SKYBLUE (-3375 3875);
DISPLAY INVISIBLE (-3375 3875);
FORCEADD Q_RES..1
(-3625 3975);
FORCEPROP 1 LAST LOCATION R1643
J 0
(-4000 3975);
DISPLAY 0.489362 (-4000 3975);
PAINT SKYBLUE (-4000 3975);
FORCEPROP 0 LAST $SEC 1
J 0
(-3950 4025);
DISPLAY 0.680851 (-3950 4025);
PAINT MONO (-3950 4025);
DISPLAY INVISIBLE (-3950 4025);
FORCEPROP 0 LAST CDS_SEC 1
J 0
(-3950 4025);
DISPLAY 1.021277 (-3950 4025);
DISPLAY INVISIBLE (-3950 4025);
FORCEPROP 1 LASTPIN (-3725 3975) $PN 1
J 0
(-3713 3987);
DISPLAY 0.489362 (-3713 3987);
PAINT MONO (-3713 3987);
FORCEPROP 1 LASTPIN (-3525 3975) $PN 2
J 0
(-3563 3987);
DISPLAY 0.489362 (-3563 3987);
PAINT MONO (-3563 3987);
FORCEPROP 1 LAST MATERIAL CHIP
J 0
(-3800 3950);
DISPLAY 0.489362 (-3800 3950);
PAINT SKYBLUE (-3800 3950);
FORCEPROP 1 LAST TOLERANCE 1%
J 0
(-3525 3950);
DISPLAY 0.489362 (-3525 3950);
PAINT SKYBLUE (-3525 3950);
FORCEPROP 1 LAST VALUE 22
J 2
(-3725 3975);
DISPLAY 0.489362 (-3725 3975);
PAINT SKYBLUE (-3725 3975);
FORCEPROP 2 LAST CDS_LIB pure_quanta
J 0
(-3625 3975);
DISPLAY INVISIBLE (-3625 3975);
FORCEPROP 1 LAST PATH I34
J 0
(-3675 4125);
DISPLAY 0.978723 (-3675 4125);
PAINT WHITE (-3675 4125);
DISPLAY INVISIBLE (-3675 4125);
FORCEPROP 1 LAST WATTAGE 1/16W
J 2
(-3650 3825);
DISPLAY 0.978723 (-3650 3825);
PAINT SKYBLUE (-3650 3825);
DISPLAY INVISIBLE (-3650 3825);
FORCEPROP 1 LAST PART_NUMBER CS02202FB12
J 0
(-3675 4075);
DISPLAY 0.978723 (-3675 4075);
PAINT SKYBLUE (-3675 4075);
DISPLAY INVISIBLE (-3675 4075);
FORCEPROP 1 LAST PACK_TYPE 0402LF
J 0
(-3375 3825);
DISPLAY 0.978723 (-3375 3825);
PAINT SKYBLUE (-3375 3825);
DISPLAY INVISIBLE (-3375 3825);
FORCEADD Q_RES..1
(-3625 3925);
FORCEPROP 1 LAST LOCATION R1644
J 0
(-4000 3925);
DISPLAY 0.489362 (-4000 3925);
PAINT SKYBLUE (-4000 3925);
FORCEPROP 0 LAST $SEC 1
J 0
(-3875 3975);
PAINT MONO (-3875 3975);
DISPLAY INVISIBLE (-3875 3975);
FORCEPROP 0 LAST CDS_SEC 1
J 0
(-3875 3975);
PAINT MONO (-3875 3975);
DISPLAY INVISIBLE (-3875 3975);
FORCEPROP 1 LASTPIN (-3725 3925) $PN 1
J 0
(-3713 3937);
DISPLAY 0.489362 (-3713 3937);
PAINT GREEN (-3713 3937);
FORCEPROP 1 LASTPIN (-3525 3925) $PN 2
J 0
(-3563 3937);
DISPLAY 0.489362 (-3563 3937);
PAINT GREEN (-3563 3937);
FORCEPROP 1 LAST MATERIAL CHIP
J 0
(-3800 3900);
DISPLAY 0.489362 (-3800 3900);
PAINT SKYBLUE (-3800 3900);
FORCEPROP 1 LAST TOLERANCE 1%
J 0
(-3525 3900);
DISPLAY 0.489362 (-3525 3900);
PAINT SKYBLUE (-3525 3900);
FORCEPROP 1 LAST VALUE 22
J 2
(-3725 3925);
DISPLAY 0.489362 (-3725 3925);
PAINT SKYBLUE (-3725 3925);
FORCEPROP 2 LAST CDS_LIB pure_quanta
J 0
(-3625 3925);
PAINT MONO (-3625 3925);
DISPLAY INVISIBLE (-3625 3925);
FORCEPROP 1 LAST PATH I35
J 0
(-3675 4075);
DISPLAY 0.978723 (-3675 4075);
PAINT WHITE (-3675 4075);
DISPLAY INVISIBLE (-3675 4075);
FORCEPROP 1 LAST WATTAGE 1/16W
J 2
(-3650 3775);
DISPLAY 0.978723 (-3650 3775);
PAINT SKYBLUE (-3650 3775);
DISPLAY INVISIBLE (-3650 3775);
FORCEPROP 1 LAST PART_NUMBER CS02202FB12
J 0
(-3675 4025);
DISPLAY 0.978723 (-3675 4025);
PAINT SKYBLUE (-3675 4025);
DISPLAY INVISIBLE (-3675 4025);
FORCEPROP 1 LAST PACK_TYPE 0402LF
J 0
(-3375 3775);
DISPLAY 0.978723 (-3375 3775);
PAINT SKYBLUE (-3375 3775);
DISPLAY INVISIBLE (-3375 3775);
FORCEADD Q_RES..1
(-3625 3875);
FORCEPROP 1 LAST LOCATION R1645
J 0
(-4000 3875);
DISPLAY 0.489362 (-4000 3875);
PAINT SKYBLUE (-4000 3875);
FORCEPROP 0 LAST $SEC 1
J 0
(-3875 3925);
PAINT MONO (-3875 3925);
DISPLAY INVISIBLE (-3875 3925);
FORCEPROP 0 LAST CDS_SEC 1
J 0
(-3875 3925);
PAINT MONO (-3875 3925);
DISPLAY INVISIBLE (-3875 3925);
FORCEPROP 1 LASTPIN (-3725 3875) $PN 1
J 0
(-3713 3887);
DISPLAY 0.489362 (-3713 3887);
PAINT GREEN (-3713 3887);
FORCEPROP 1 LASTPIN (-3525 3875) $PN 2
J 0
(-3563 3887);
DISPLAY 0.489362 (-3563 3887);
PAINT GREEN (-3563 3887);
FORCEPROP 1 LAST MATERIAL CHIP
J 0
(-3800 3850);
DISPLAY 0.489362 (-3800 3850);
PAINT SKYBLUE (-3800 3850);
FORCEPROP 1 LAST TOLERANCE 1%
J 0
(-3525 3850);
DISPLAY 0.489362 (-3525 3850);
PAINT SKYBLUE (-3525 3850);
FORCEPROP 1 LAST VALUE 22
J 2
(-3725 3875);
DISPLAY 0.489362 (-3725 3875);
PAINT SKYBLUE (-3725 3875);
FORCEPROP 2 LAST CDS_LIB pure_quanta
J 0
(-3625 3875);
PAINT MONO (-3625 3875);
DISPLAY INVISIBLE (-3625 3875);
FORCEPROP 1 LAST PATH I36
J 0
(-3675 4025);
DISPLAY 0.978723 (-3675 4025);
PAINT WHITE (-3675 4025);
DISPLAY INVISIBLE (-3675 4025);
FORCEPROP 1 LAST WATTAGE 1/16W
J 2
(-3650 3725);
DISPLAY 0.978723 (-3650 3725);
PAINT SKYBLUE (-3650 3725);
DISPLAY INVISIBLE (-3650 3725);
FORCEPROP 1 LAST PART_NUMBER CS02202FB12
J 0
(-3675 3975);
DISPLAY 0.978723 (-3675 3975);
PAINT SKYBLUE (-3675 3975);
DISPLAY INVISIBLE (-3675 3975);
FORCEPROP 1 LAST PACK_TYPE 0402LF
J 0
(-3375 3725);
DISPLAY 0.978723 (-3375 3725);
PAINT SKYBLUE (-3375 3725);
DISPLAY INVISIBLE (-3375 3725);
FORCEADD UNIVERSAL_POWER..1
(-4800 4725);
FORCEPROP 3 LASTPIN (-4800 4675) SIG_NAME PVDD18_S5_P0\g
J 0
(-4790 4685);
DISPLAY 0.659574 (-4790 4685);
PAINT MONO (-4790 4685);
DISPLAY INVISIBLE (-4790 4685);
FORCEPROP 1 LAST HDL_POWER PVDD18_S5_P0
J 1
(-4800 4775);
DISPLAY 0.489362 (-4800 4775);
PAINT GREEN (-4800 4775);
FORCEPROP 2 LAST CDS_LIB pure_quanta_power
J 0
(-4800 4725);
PAINT MONO (-4800 4725);
DISPLAY INVISIBLE (-4800 4725);
FORCEPROP 1 LAST PATH I37
J 0
(-4750 4750);
DISPLAY 0.872340 (-4750 4750);
PAINT AQUA (-4750 4750);
DISPLAY INVISIBLE (-4750 4750);
FORCEADD UNIVERSAL_POWER..1
(-5850 4725);
FORCEPROP 3 LASTPIN (-5850 4675) SIG_NAME PVDD18_S5_P0\g
J 0
(-5840 4685);
DISPLAY 0.659574 (-5840 4685);
PAINT MONO (-5840 4685);
DISPLAY INVISIBLE (-5840 4685);
FORCEPROP 1 LAST HDL_POWER PVDD18_S5_P0
J 1
(-5850 4775);
DISPLAY 0.489362 (-5850 4775);
PAINT GREEN (-5850 4775);
FORCEPROP 2 LAST CDS_LIB pure_quanta_power
J 0
(-5850 4725);
PAINT MONO (-5850 4725);
DISPLAY INVISIBLE (-5850 4725);
FORCEPROP 1 LAST PATH I38
J 0
(-5800 4750);
DISPLAY 0.872340 (-5800 4750);
PAINT AQUA (-5800 4750);
DISPLAY INVISIBLE (-5800 4750);
FORCEADD GND..1
(-4650 4175);
FORCEPROP 3 LASTPIN (-4650 4225) SIG_NAME GND\g
J 0
(-4640 4235);
DISPLAY 0.659574 (-4640 4235);
PAINT MONO (-4640 4235);
DISPLAY INVISIBLE (-4640 4235);
FORCEPROP 2 LAST CDS_LIB pure_quanta_power
J 0
(-4650 4175);
DISPLAY INVISIBLE (-4650 4175);
FORCEPROP 1 LAST SIZE 1B
J 0
(-4575 4125);
DISPLAY 0.872340 (-4575 4125);
PAINT GREEN (-4575 4125);
DISPLAY INVISIBLE (-4575 4125);
FORCEPROP 1 LAST PATH I39
J 0
(-4575 4175);
DISPLAY 0.872340 (-4575 4175);
PAINT AQUA (-4575 4175);
DISPLAY INVISIBLE (-4575 4175);
FORCEPROP 1 LAST HDL_POWER GND
J 0
(-4650 4325);
DISPLAY 0.872340 (-4650 4325);
PAINT GREEN (-4650 4325);
DISPLAY INVISIBLE (-4650 4325);
FORCEADD Q_CAP..1
(-4650 4400);
FORCEPROP 1 LAST LOCATION C1517
J 0
(-4550 4550);
DISPLAY 0.489362 (-4550 4550);
PAINT SKYBLUE (-4550 4550);
FORCEPROP 2 LAST $SEC 1
J 0
(-4600 4600);
PAINT MONO (-4600 4600);
DISPLAY INVISIBLE (-4600 4600);
FORCEPROP 2 LAST CDS_SEC 1
J 0
(-4600 4600);
PAINT MONO (-4600 4600);
DISPLAY INVISIBLE (-4600 4600);
FORCEPROP 1 LASTPIN (-4650 4500) $PN 1
J 0
(-4640 4480);
DISPLAY 0.489362 (-4640 4480);
PAINT GREEN (-4640 4480);
FORCEPROP 1 LASTPIN (-4650 4300) $PN 2
J 0
(-4640 4280);
DISPLAY 0.489362 (-4640 4280);
PAINT GREEN (-4640 4280);
FORCEPROP 1 LAST MATERIAL X7R
J 0
(-4550 4350);
DISPLAY 0.489362 (-4550 4350);
PAINT SKYBLUE (-4550 4350);
FORCEPROP 1 LAST TOLERANCE 10%
J 0
(-4550 4400);
DISPLAY 0.489362 (-4550 4400);
PAINT SKYBLUE (-4550 4400);
FORCEPROP 1 LAST VALUE 0.1UF
J 0
(-4550 4500);
DISPLAY 0.489362 (-4550 4500);
PAINT SKYBLUE (-4550 4500);
FORCEPROP 1 LAST PART_NUMBER CH4103K1B08
J 0
(-4550 4300);
DISPLAY 0.489362 (-4550 4300);
PAINT SKYBLUE (-4550 4300);
FORCEPROP 1 LAST VOLTAGE 16V
J 0
(-4550 4450);
DISPLAY 0.489362 (-4550 4450);
PAINT SKYBLUE (-4550 4450);
FORCEPROP 1 LAST PACK_TYPE C0402
J 0
(-4550 4250);
DISPLAY 0.489362 (-4550 4250);
PAINT SKYBLUE (-4550 4250);
FORCEPROP 2 LAST CDS_LIB pure_quanta
J 0
(-4650 4400);
DISPLAY INVISIBLE (-4650 4400);
FORCEPROP 1 LAST PATH I40
J 0
(-4600 4550);
DISPLAY 0.978723 (-4600 4550);
PAINT WHITE (-4600 4550);
DISPLAY INVISIBLE (-4600 4550);
FORCEADD GND..1
(-4800 3350);
FORCEPROP 3 LASTPIN (-4800 3400) SIG_NAME GND\g
J 0
(-4790 3410);
DISPLAY 0.659574 (-4790 3410);
PAINT MONO (-4790 3410);
DISPLAY INVISIBLE (-4790 3410);
FORCEPROP 1 LAST SIZE 1B
J 0
(-4725 3300);
DISPLAY 0.872340 (-4725 3300);
PAINT GREEN (-4725 3300);
DISPLAY INVISIBLE (-4725 3300);
FORCEPROP 2 LAST CDS_LIB pure_quanta_power
J 0
(-4800 3350);
PAINT MONO (-4800 3350);
DISPLAY INVISIBLE (-4800 3350);
FORCEPROP 1 LAST PATH I41
J 0
(-4725 3350);
DISPLAY 0.872340 (-4725 3350);
PAINT AQUA (-4725 3350);
DISPLAY INVISIBLE (-4725 3350);
FORCEPROP 1 LAST HDL_POWER GND
J 0
(-4800 3500);
DISPLAY 0.872340 (-4800 3500);
PAINT GREEN (-4800 3500);
DISPLAY INVISIBLE (-4800 3500);
FORCEADD GND..1
(-6050 4225);
FORCEPROP 3 LASTPIN (-6050 4275) SIG_NAME GND\g
J 0
(-6040 4285);
DISPLAY 0.659574 (-6040 4285);
PAINT MONO (-6040 4285);
DISPLAY INVISIBLE (-6040 4285);
FORCEPROP 2 LAST CDS_LIB pure_quanta_power
J 0
(-6050 4225);
DISPLAY INVISIBLE (-6050 4225);
FORCEPROP 1 LAST SIZE 1B
J 0
(-5975 4175);
DISPLAY 0.872340 (-5975 4175);
PAINT GREEN (-5975 4175);
DISPLAY INVISIBLE (-5975 4175);
FORCEPROP 1 LAST PATH I42
J 0
(-5975 4225);
DISPLAY 0.872340 (-5975 4225);
PAINT AQUA (-5975 4225);
DISPLAY INVISIBLE (-5975 4225);
FORCEPROP 1 LAST HDL_POWER GND
J 0
(-6050 4375);
DISPLAY 0.872340 (-6050 4375);
PAINT GREEN (-6050 4375);
DISPLAY INVISIBLE (-6050 4375);
FORCEADD Q_CAP..1
(-6050 4450);
FORCEPROP 1 LAST LOCATION C1515
J 0
(-6200 4575);
DISPLAY 0.489362 (-6200 4575);
PAINT SKYBLUE (-6200 4575);
FORCEPROP 2 LAST $SEC 1
J 0
(-6000 4650);
PAINT MONO (-6000 4650);
DISPLAY INVISIBLE (-6000 4650);
FORCEPROP 2 LAST CDS_SEC 1
J 0
(-6000 4650);
PAINT MONO (-6000 4650);
DISPLAY INVISIBLE (-6000 4650);
FORCEPROP 1 LASTPIN (-6050 4550) $PN 1
J 0
(-6040 4530);
DISPLAY 0.489362 (-6040 4530);
PAINT GREEN (-6040 4530);
FORCEPROP 1 LASTPIN (-6050 4350) $PN 2
J 0
(-6040 4330);
DISPLAY 0.489362 (-6040 4330);
PAINT GREEN (-6040 4330);
FORCEPROP 1 LAST MATERIAL X7R
J 0
(-6175 4375);
DISPLAY 0.489362 (-6175 4375);
PAINT SKYBLUE (-6175 4375);
FORCEPROP 1 LAST TOLERANCE 10%
J 0
(-6175 4425);
DISPLAY 0.489362 (-6175 4425);
PAINT SKYBLUE (-6175 4425);
FORCEPROP 1 LAST VALUE 0.1UF
J 0
(-6225 4525);
DISPLAY 0.489362 (-6225 4525);
PAINT SKYBLUE (-6225 4525);
FORCEPROP 1 LAST PART_NUMBER CH4103K1B08
J 0
(-6400 4325);
DISPLAY 0.489362 (-6400 4325);
PAINT SKYBLUE (-6400 4325);
FORCEPROP 1 LAST VOLTAGE 16V
J 0
(-6175 4475);
DISPLAY 0.489362 (-6175 4475);
PAINT SKYBLUE (-6175 4475);
FORCEPROP 1 LAST PACK_TYPE C0402
J 0
(-6225 4275);
DISPLAY 0.489362 (-6225 4275);
PAINT SKYBLUE (-6225 4275);
FORCEPROP 2 LAST CDS_LIB pure_quanta
J 0
(-6050 4450);
DISPLAY INVISIBLE (-6050 4450);
FORCEPROP 1 LAST PATH I43
J 0
(-6000 4600);
DISPLAY 0.978723 (-6000 4600);
PAINT WHITE (-6000 4600);
DISPLAY INVISIBLE (-6000 4600);
FORCEADD SN74AVC2T245RSWR..1
R 2
(-5325 2175);
FORCEPROP 1 LAST LOCATION U152
J 2
(-5080 2715);
DISPLAY 0.489362 (-5080 2715);
PAINT SKYBLUE (-5080 2715);
FORCEPROP 0 LAST $SEC 1
J 0
(-5075 2875);
DISPLAY 0.680851 (-5075 2875);
PAINT MONO (-5075 2875);
DISPLAY INVISIBLE (-5075 2875);
FORCEPROP 0 LAST CDS_SEC 1
J 0
(-5075 2875);
DISPLAY 1.021277 (-5075 2875);
DISPLAY INVISIBLE (-5075 2875);
FORCEPROP 0 LASTPIN (-5725 2300) $PN 8
J 2
(-5735 2310);
DISPLAY 0.489362 (-5735 2310);
PAINT MONO (-5735 2310);
FORCEPROP 0 LASTPIN (-5725 2150) $PN 9
J 2
(-5735 2160);
DISPLAY 0.489362 (-5735 2160);
PAINT MONO (-5735 2160);
FORCEPROP 0 LASTPIN (-4925 2250) $PN 5
J 0
(-4915 2260);
DISPLAY 0.489362 (-4915 2260);
PAINT MONO (-4915 2260);
FORCEPROP 0 LASTPIN (-4925 2100) $PN 4
J 0
(-4915 2110);
DISPLAY 0.489362 (-4915 2110);
PAINT MONO (-4915 2110);
FORCEPROP 0 LASTPIN (-5725 2250) $PN 10
J 2
(-5735 2260);
DISPLAY 0.489362 (-5735 2260);
PAINT MONO (-5735 2260);
FORCEPROP 0 LASTPIN (-5725 2100) $PN 1
J 2
(-5735 2110);
DISPLAY 0.489362 (-5735 2110);
PAINT MONO (-5735 2110);
FORCEPROP 0 LASTPIN (-5725 1850) $PN 3
J 2
(-5735 1860);
DISPLAY 0.489362 (-5735 1860);
PAINT MONO (-5735 1860);
FORCEPROP 0 LASTPIN (-5725 2000) $PN 2
J 2
(-5735 2010);
DISPLAY 0.489362 (-5735 2010);
PAINT MONO (-5735 2010);
FORCEPROP 0 LASTPIN (-4925 2500) $PN 7
J 0
(-4915 2510);
DISPLAY 0.489362 (-4915 2510);
PAINT MONO (-4915 2510);
FORCEPROP 0 LASTPIN (-4925 2450) $PN 6
J 0
(-4915 2460);
DISPLAY 0.489362 (-4915 2460);
PAINT MONO (-4915 2460);
FORCEPROP 2 LAST PART_TYPE SMLF
J 2
(-5075 2825);
PAINT MONO (-5075 2825);
FORCEPROP 1 LAST MATERIAL IC
J 2
(-5080 2557);
DISPLAY 0.489362 (-5080 2557);
PAINT SKYBLUE (-5080 2557);
FORCEPROP 2 LAST VALUE SN74AVC2T245RSWR
J 2
(-5075 2775);
DISPLAY 0.489362 (-5075 2775);
PAINT SKYBLUE (-5075 2775);
FORCEPROP 1 LAST PART_NUMBER AL02T245000
J 2
(-5080 2626);
DISPLAY 0.489362 (-5080 2626);
PAINT SKYBLUE (-5080 2626);
FORCEPROP 2 LAST CDS_LIB pure_quanta
J 0
(-5325 2175);
DISPLAY INVISIBLE (-5325 2175);
FORCEPROP 1 LAST CDS_LMAN_SYM_OUTLINE -250,375,250,-375
J 2
(-5325 2175);
DISPLAY 0.468085 (-5325 2175);
PAINT GREEN (-5325 2175);
DISPLAY INVISIBLE (-5325 2175);
FORCEPROP 1 LAST NEEDS_NO_SIZE TRUE
J 2
(-5575 1857);
DISPLAY 0.723404 (-5575 1857);
PAINT GREEN (-5575 1857);
DISPLAY INVISIBLE (-5575 1857);
FORCEPROP 1 LAST PATH I60
J 2
(-5575 1800);
DISPLAY 0.723404 (-5575 1800);
PAINT GREEN (-5575 1800);
DISPLAY INVISIBLE (-5575 1800);
FORCEADD OFFPAGE..1
(-6700 2300);
FORCEPROP 2 LAST $XR0 149 
J 0
(-6982 2300);
DISPLAY 0.638298 (-6982 2300);
PAINT MONO (-6982 2300);
FORCEPROP 2 LAST CDS_LIB standard
J 2
(-6700 2300);
DISPLAY INVISIBLE (-6700 2300);
FORCEPROP 1 LAST OFFPAGE TRUE
J 0
(-6375 2175);
DISPLAY 0.872340 (-6375 2175);
PAINT GREEN (-6375 2175);
DISPLAY INVISIBLE (-6375 2175);
FORCEPROP 1 LAST COMMENT_BODY TRUE
J 0
(-6575 2200);
DISPLAY 0.872340 (-6575 2200);
PAINT GREEN (-6575 2200);
DISPLAY INVISIBLE (-6575 2200);
FORCEPROP 2 LAST PATH I61
J 0
(-6650 2375);
DISPLAY 1.021277 (-6650 2375);
DISPLAY INVISIBLE (-6650 2375);
FORCEADD OFFPAGE..2
R 2
(-6700 2150);
FORCEPROP 2 LAST $XR0 149 
J 0
(-6955 2150);
DISPLAY 0.638298 (-6955 2150);
PAINT MONO (-6955 2150);
FORCEPROP 2 LAST CDS_LIB standard
J 2
(-6700 2150);
DISPLAY INVISIBLE (-6700 2150);
FORCEPROP 1 LAST OFFPAGE TRUE
J 2
(-7025 2025);
DISPLAY 0.872340 (-7025 2025);
PAINT GREEN (-7025 2025);
DISPLAY INVISIBLE (-7025 2025);
FORCEPROP 1 LAST COMMENT_BODY TRUE
J 2
(-6655 2055);
DISPLAY 0.872340 (-6655 2055);
PAINT GREEN (-6655 2055);
DISPLAY INVISIBLE (-6655 2055);
FORCEPROP 2 LAST PATH I62
J 2
(-6875 2225);
DISPLAY 1.021277 (-6875 2225);
DISPLAY INVISIBLE (-6875 2225);
FORCEADD GND..1
(-6025 1750);
FORCEPROP 3 LASTPIN (-6025 1800) SIG_NAME GND\g
J 0
(-6015 1810);
DISPLAY 0.659574 (-6015 1810);
PAINT MONO (-6015 1810);
DISPLAY INVISIBLE (-6015 1810);
FORCEPROP 1 LAST SIZE 1B
J 0
(-5950 1700);
DISPLAY 0.872340 (-5950 1700);
PAINT GREEN (-5950 1700);
DISPLAY INVISIBLE (-5950 1700);
FORCEPROP 2 LAST CDS_LIB pure_quanta_power
J 0
(-6025 1750);
PAINT MONO (-6025 1750);
DISPLAY INVISIBLE (-6025 1750);
FORCEPROP 1 LAST PATH I63
J 0
(-5950 1750);
DISPLAY 0.872340 (-5950 1750);
PAINT AQUA (-5950 1750);
DISPLAY INVISIBLE (-5950 1750);
FORCEPROP 1 LAST HDL_POWER GND
J 0
(-6025 1900);
DISPLAY 0.872340 (-6025 1900);
PAINT GREEN (-6025 1900);
DISPLAY INVISIBLE (-6025 1900);
FORCEADD UNIVERSAL_POWER..1
(-4775 2975);
FORCEPROP 3 LASTPIN (-4775 2925) SIG_NAME PVDD18_S5_P0\g
J 0
(-4765 2935);
DISPLAY 0.659574 (-4765 2935);
PAINT MONO (-4765 2935);
DISPLAY INVISIBLE (-4765 2935);
FORCEPROP 1 LAST HDL_POWER PVDD18_S5_P0
J 1
(-4750 3025);
DISPLAY 0.489362 (-4750 3025);
PAINT GREEN (-4750 3025);
FORCEPROP 2 LAST CDS_LIB pure_quanta_power
J 0
(-4775 2975);
PAINT MONO (-4775 2975);
DISPLAY INVISIBLE (-4775 2975);
FORCEPROP 1 LAST PATH I64
J 0
(-4725 3000);
DISPLAY 0.872340 (-4725 3000);
PAINT AQUA (-4725 3000);
DISPLAY INVISIBLE (-4725 3000);
FORCEADD GND..1
(-4650 2475);
FORCEPROP 3 LASTPIN (-4650 2525) SIG_NAME GND\g
J 0
(-4640 2535);
DISPLAY 0.659574 (-4640 2535);
PAINT MONO (-4640 2535);
DISPLAY INVISIBLE (-4640 2535);
FORCEPROP 2 LAST CDS_LIB pure_quanta_power
J 0
(-4650 2475);
DISPLAY INVISIBLE (-4650 2475);
FORCEPROP 1 LAST SIZE 1B
J 0
(-4575 2425);
DISPLAY 0.872340 (-4575 2425);
PAINT GREEN (-4575 2425);
DISPLAY INVISIBLE (-4575 2425);
FORCEPROP 1 LAST PATH I65
J 0
(-4575 2475);
DISPLAY 0.872340 (-4575 2475);
PAINT AQUA (-4575 2475);
DISPLAY INVISIBLE (-4575 2475);
FORCEPROP 1 LAST HDL_POWER GND
J 0
(-4650 2625);
DISPLAY 0.872340 (-4650 2625);
PAINT GREEN (-4650 2625);
DISPLAY INVISIBLE (-4650 2625);
FORCEADD Q_CAP..1
(-4650 2700);
FORCEPROP 1 LAST LOCATION C1518
J 0
(-4550 2850);
DISPLAY 0.489362 (-4550 2850);
PAINT SKYBLUE (-4550 2850);
FORCEPROP 2 LAST $SEC 1
J 0
(-4600 2900);
PAINT MONO (-4600 2900);
DISPLAY INVISIBLE (-4600 2900);
FORCEPROP 2 LAST CDS_SEC 1
J 0
(-4600 2900);
PAINT MONO (-4600 2900);
DISPLAY INVISIBLE (-4600 2900);
FORCEPROP 1 LASTPIN (-4650 2800) $PN 1
J 0
(-4640 2780);
DISPLAY 0.489362 (-4640 2780);
PAINT GREEN (-4640 2780);
FORCEPROP 1 LASTPIN (-4650 2600) $PN 2
J 0
(-4640 2580);
DISPLAY 0.489362 (-4640 2580);
PAINT GREEN (-4640 2580);
FORCEPROP 1 LAST MATERIAL X7R
J 0
(-4550 2650);
DISPLAY 0.489362 (-4550 2650);
PAINT SKYBLUE (-4550 2650);
FORCEPROP 1 LAST TOLERANCE 10%
J 0
(-4550 2700);
DISPLAY 0.489362 (-4550 2700);
PAINT SKYBLUE (-4550 2700);
FORCEPROP 1 LAST VALUE 0.1UF
J 0
(-4550 2800);
DISPLAY 0.489362 (-4550 2800);
PAINT SKYBLUE (-4550 2800);
FORCEPROP 1 LAST PART_NUMBER CH4103K1B08
J 0
(-4550 2600);
DISPLAY 0.489362 (-4550 2600);
PAINT SKYBLUE (-4550 2600);
FORCEPROP 1 LAST VOLTAGE 16V
J 0
(-4550 2750);
DISPLAY 0.489362 (-4550 2750);
PAINT SKYBLUE (-4550 2750);
FORCEPROP 1 LAST PACK_TYPE C0402
J 0
(-4550 2550);
DISPLAY 0.489362 (-4550 2550);
PAINT SKYBLUE (-4550 2550);
FORCEPROP 2 LAST CDS_LIB pure_quanta
J 0
(-4650 2700);
DISPLAY INVISIBLE (-4650 2700);
FORCEPROP 1 LAST PATH I66
J 0
(-4600 2850);
DISPLAY 0.978723 (-4600 2850);
PAINT WHITE (-4600 2850);
DISPLAY INVISIBLE (-4600 2850);
FORCEADD UNIVERSAL_POWER..1
(-6025 2975);
FORCEPROP 3 LASTPIN (-6025 2925) SIG_NAME PVDD18_S5_P0\g
J 0
(-6015 2935);
DISPLAY 0.659574 (-6015 2935);
PAINT MONO (-6015 2935);
DISPLAY INVISIBLE (-6015 2935);
FORCEPROP 1 LAST HDL_POWER PVDD18_S5_P0
J 1
(-6025 3025);
DISPLAY 0.489362 (-6025 3025);
PAINT GREEN (-6025 3025);
FORCEPROP 2 LAST CDS_LIB pure_quanta_power
J 0
(-6025 2975);
PAINT MONO (-6025 2975);
DISPLAY INVISIBLE (-6025 2975);
FORCEPROP 1 LAST PATH I67
J 0
(-5975 3000);
DISPLAY 0.872340 (-5975 3000);
PAINT AQUA (-5975 3000);
DISPLAY INVISIBLE (-5975 3000);
FORCEADD GND..1
(-6225 2475);
FORCEPROP 3 LASTPIN (-6225 2525) SIG_NAME GND\g
J 0
(-6215 2535);
DISPLAY 0.659574 (-6215 2535);
PAINT MONO (-6215 2535);
DISPLAY INVISIBLE (-6215 2535);
FORCEPROP 2 LAST CDS_LIB pure_quanta_power
J 0
(-6225 2475);
DISPLAY INVISIBLE (-6225 2475);
FORCEPROP 1 LAST SIZE 1B
J 0
(-6150 2425);
DISPLAY 0.872340 (-6150 2425);
PAINT GREEN (-6150 2425);
DISPLAY INVISIBLE (-6150 2425);
FORCEPROP 1 LAST PATH I68
J 0
(-6150 2475);
DISPLAY 0.872340 (-6150 2475);
PAINT AQUA (-6150 2475);
DISPLAY INVISIBLE (-6150 2475);
FORCEPROP 1 LAST HDL_POWER GND
J 0
(-6225 2625);
DISPLAY 0.872340 (-6225 2625);
PAINT GREEN (-6225 2625);
DISPLAY INVISIBLE (-6225 2625);
FORCEADD Q_CAP..1
(-6225 2700);
FORCEPROP 1 LAST LOCATION C1513
J 0
(-6375 2825);
DISPLAY 0.489362 (-6375 2825);
PAINT SKYBLUE (-6375 2825);
FORCEPROP 2 LAST $SEC 1
J 0
(-6175 2900);
PAINT MONO (-6175 2900);
DISPLAY INVISIBLE (-6175 2900);
FORCEPROP 2 LAST CDS_SEC 1
J 0
(-6175 2900);
PAINT MONO (-6175 2900);
DISPLAY INVISIBLE (-6175 2900);
FORCEPROP 1 LASTPIN (-6225 2800) $PN 1
J 0
(-6215 2780);
DISPLAY 0.489362 (-6215 2780);
PAINT GREEN (-6215 2780);
FORCEPROP 1 LASTPIN (-6225 2600) $PN 2
J 0
(-6215 2580);
DISPLAY 0.489362 (-6215 2580);
PAINT GREEN (-6215 2580);
FORCEPROP 1 LAST MATERIAL X7R
J 0
(-6350 2625);
DISPLAY 0.489362 (-6350 2625);
PAINT SKYBLUE (-6350 2625);
FORCEPROP 1 LAST TOLERANCE 10%
J 0
(-6350 2675);
DISPLAY 0.489362 (-6350 2675);
PAINT SKYBLUE (-6350 2675);
FORCEPROP 1 LAST VALUE 0.1UF
J 0
(-6400 2775);
DISPLAY 0.489362 (-6400 2775);
PAINT SKYBLUE (-6400 2775);
FORCEPROP 1 LAST PART_NUMBER CH4103K1B08
J 0
(-6575 2575);
DISPLAY 0.489362 (-6575 2575);
PAINT SKYBLUE (-6575 2575);
FORCEPROP 1 LAST VOLTAGE 16V
J 0
(-6350 2725);
DISPLAY 0.489362 (-6350 2725);
PAINT SKYBLUE (-6350 2725);
FORCEPROP 1 LAST PACK_TYPE C0402
J 0
(-6400 2525);
DISPLAY 0.489362 (-6400 2525);
PAINT SKYBLUE (-6400 2525);
FORCEPROP 2 LAST CDS_LIB pure_quanta
J 0
(-6225 2700);
DISPLAY INVISIBLE (-6225 2700);
FORCEPROP 1 LAST PATH I69
J 0
(-6175 2850);
DISPLAY 0.978723 (-6175 2850);
PAINT WHITE (-6175 2850);
DISPLAY INVISIBLE (-6175 2850);
FORCEADD GND..1
(-6600 1525);
FORCEPROP 3 LASTPIN (-6600 1575) SIG_NAME GND\g
J 0
(-6590 1585);
DISPLAY 0.659574 (-6590 1585);
PAINT MONO (-6590 1585);
DISPLAY INVISIBLE (-6590 1585);
FORCEPROP 1 LAST SIZE 1B
J 0
(-6525 1475);
DISPLAY 0.872340 (-6525 1475);
PAINT GREEN (-6525 1475);
DISPLAY INVISIBLE (-6525 1475);
FORCEPROP 2 LAST CDS_LIB pure_quanta_power
J 0
(-6600 1525);
PAINT MONO (-6600 1525);
DISPLAY INVISIBLE (-6600 1525);
FORCEPROP 1 LAST PATH I70
J 0
(-6525 1525);
DISPLAY 0.872340 (-6525 1525);
PAINT AQUA (-6525 1525);
DISPLAY INVISIBLE (-6525 1525);
FORCEPROP 1 LAST HDL_POWER GND
J 0
(-6600 1675);
DISPLAY 0.872340 (-6600 1675);
PAINT GREEN (-6600 1675);
DISPLAY INVISIBLE (-6600 1675);
FORCEADD Q_RES..2
R 2
(-6600 1800);
FORCEPROP 1 LAST LOCATION R1637
J 2
(-6645 1925);
DISPLAY 0.489362 (-6645 1925);
PAINT SKYBLUE (-6645 1925);
FORCEPROP 0 LAST $SEC 1
J 0
(-6625 1975);
DISPLAY 0.680851 (-6625 1975);
PAINT MONO (-6625 1975);
DISPLAY INVISIBLE (-6625 1975);
FORCEPROP 0 LAST CDS_SEC 1
J 0
(-6625 1975);
DISPLAY 1.021277 (-6625 1975);
DISPLAY INVISIBLE (-6625 1975);
FORCEPROP 1 LASTPIN (-6600 1900) $PN 1
J 2
(-6605 1862);
DISPLAY 0.489362 (-6605 1862);
PAINT MONO (-6605 1862);
FORCEPROP 1 LASTPIN (-6600 1700) $PN 2
J 2
(-6605 1710);
DISPLAY 0.489362 (-6605 1710);
PAINT MONO (-6605 1710);
FORCEPROP 1 LAST WATTAGE 1/16W
J 2
(-6640 1775);
DISPLAY 0.489362 (-6640 1775);
PAINT SKYBLUE (-6640 1775);
FORCEPROP 1 LAST MATERIAL CHIP
J 2
(-6640 1725);
DISPLAY 0.489362 (-6640 1725);
PAINT SKYBLUE (-6640 1725);
FORCEPROP 1 LAST TOLERANCE 5%
J 2
(-6650 1825);
DISPLAY 0.489362 (-6650 1825);
PAINT SKYBLUE (-6650 1825);
FORCEPROP 1 LAST VALUE 4.7K
J 2
(-6650 1875);
DISPLAY 0.489362 (-6650 1875);
PAINT SKYBLUE (-6650 1875);
FORCEPROP 1 LAST PART_NUMBER TMP_QCS24702JB38
J 2
(-6640 1675);
DISPLAY 0.489362 (-6640 1675);
PAINT SKYBLUE (-6640 1675);
FORCEPROP 1 LAST PACK_TYPE 0402LF
J 2
(-6640 1625);
DISPLAY 0.489362 (-6640 1625);
PAINT SKYBLUE (-6640 1625);
FORCEPROP 2 LAST CDS_LIB pure_quanta
J 2
(-6600 1800);
DISPLAY INVISIBLE (-6600 1800);
FORCEPROP 1 LAST PATH I71
J 2
(-6650 1975);
DISPLAY 0.978723 (-6650 1975);
PAINT WHITE (-6650 1975);
DISPLAY INVISIBLE (-6650 1975);
FORCEADD OFFPAGE..2
(-3950 2250);
FORCEPROP 2 LAST $XR0 151 
J 0
(-3761 2250);
DISPLAY 0.638298 (-3761 2250);
PAINT MONO (-3761 2250);
FORCEPROP 2 LAST CDS_LIB standard
J 0
(-3950 2250);
DISPLAY INVISIBLE (-3950 2250);
FORCEPROP 1 LAST OFFPAGE TRUE
J 0
(-3625 2125);
DISPLAY 0.872340 (-3625 2125);
PAINT GREEN (-3625 2125);
DISPLAY INVISIBLE (-3625 2125);
FORCEPROP 1 LAST COMMENT_BODY TRUE
J 0
(-3995 2155);
DISPLAY 0.872340 (-3995 2155);
PAINT GREEN (-3995 2155);
DISPLAY INVISIBLE (-3995 2155);
FORCEPROP 2 LAST PATH I72
J 0
(-3775 2325);
DISPLAY 1.021277 (-3775 2325);
DISPLAY INVISIBLE (-3775 2325);
FORCEADD OFFPAGE..1
R 2
(-3950 2100);
FORCEPROP 2 LAST $XR0 151 
J 0
(-3764 2100);
DISPLAY 0.638298 (-3764 2100);
PAINT MONO (-3764 2100);
FORCEPROP 2 LAST CDS_LIB standard
J 2
(-3950 2100);
DISPLAY INVISIBLE (-3950 2100);
FORCEPROP 1 LAST OFFPAGE TRUE
J 2
(-4275 1975);
DISPLAY 0.872340 (-4275 1975);
PAINT GREEN (-4275 1975);
DISPLAY INVISIBLE (-4275 1975);
FORCEPROP 1 LAST COMMENT_BODY TRUE
J 2
(-4075 2000);
DISPLAY 0.872340 (-4075 2000);
PAINT GREEN (-4075 2000);
DISPLAY INVISIBLE (-4075 2000);
FORCEPROP 2 LAST PATH I73
J 2
(-4000 2175);
DISPLAY 1.021277 (-4000 2175);
DISPLAY INVISIBLE (-4000 2175);
FORCEADD OFFPAGE..1
(-6325 5200);
FORCEPROP 2 LAST $XR0 80 
J 0
(-6576 5200);
DISPLAY 0.638298 (-6576 5200);
PAINT MONO (-6576 5200);
FORCEPROP 2 LAST CDS_LIB standard
J 0
(-6325 5200);
DISPLAY INVISIBLE (-6325 5200);
FORCEPROP 1 LAST OFFPAGE TRUE
J 0
(-6000 5075);
DISPLAY 0.872340 (-6000 5075);
PAINT GREEN (-6000 5075);
DISPLAY INVISIBLE (-6000 5075);
FORCEPROP 1 LAST COMMENT_BODY TRUE
J 0
(-6200 5100);
DISPLAY 0.872340 (-6200 5100);
PAINT GREEN (-6200 5100);
DISPLAY INVISIBLE (-6200 5100);
FORCEPROP 2 LAST PATH I74
J 0
(-6575 5250);
DISPLAY 1.021277 (-6575 5250);
DISPLAY INVISIBLE (-6575 5250);
FORCEADD OFFPAGE..1
(-6325 3525);
FORCEPROP 2 LAST $XR0 80 
J 0
(-6576 3525);
DISPLAY 0.638298 (-6576 3525);
PAINT MONO (-6576 3525);
FORCEPROP 2 LAST CDS_LIB standard
J 0
(-6325 3525);
DISPLAY INVISIBLE (-6325 3525);
FORCEPROP 1 LAST OFFPAGE TRUE
J 0
(-6000 3400);
DISPLAY 0.872340 (-6000 3400);
PAINT GREEN (-6000 3400);
DISPLAY INVISIBLE (-6000 3400);
FORCEPROP 1 LAST COMMENT_BODY TRUE
J 0
(-6200 3425);
DISPLAY 0.872340 (-6200 3425);
PAINT GREEN (-6200 3425);
DISPLAY INVISIBLE (-6200 3425);
FORCEPROP 2 LAST PATH I75
J 0
(-6275 3600);
DISPLAY 1.021277 (-6275 3600);
DISPLAY INVISIBLE (-6275 3600);
FORCEADD SN74AVC4T774PWR..1
(-5325 5550);
FORCEPROP 1 LAST LOCATION U150
J 0
(-5572 6115);
DISPLAY 0.489362 (-5572 6115);
PAINT SKYBLUE (-5572 6115);
FORCEPROP 0 LAST $SEC 1
J 0
(-5575 6300);
DISPLAY 0.680851 (-5575 6300);
PAINT MONO (-5575 6300);
DISPLAY INVISIBLE (-5575 6300);
FORCEPROP 0 LAST CDS_SEC 1
J 0
(-5575 6300);
DISPLAY 1.021277 (-5575 6300);
DISPLAY INVISIBLE (-5575 6300);
FORCEPROP 0 LASTPIN (-5725 5700) $PN 3
J 2
(-5735 5710);
DISPLAY 0.489362 (-5735 5710);
PAINT MONO (-5735 5710);
FORCEPROP 0 LASTPIN (-5725 5650) $PN 4
J 2
(-5735 5660);
DISPLAY 0.489362 (-5735 5660);
PAINT MONO (-5735 5660);
FORCEPROP 0 LASTPIN (-5725 5600) $PN 5
J 2
(-5735 5610);
DISPLAY 0.489362 (-5735 5610);
PAINT MONO (-5735 5610);
FORCEPROP 0 LASTPIN (-5725 5550) $PN 6
J 2
(-5735 5560);
DISPLAY 0.489362 (-5735 5560);
PAINT MONO (-5735 5560);
FORCEPROP 0 LASTPIN (-4925 5700) $PN 14
J 0
(-4915 5710);
DISPLAY 0.489362 (-4915 5710);
PAINT MONO (-4915 5710);
FORCEPROP 0 LASTPIN (-4925 5650) $PN 13
J 0
(-4915 5660);
DISPLAY 0.489362 (-4915 5660);
PAINT MONO (-4915 5660);
FORCEPROP 0 LASTPIN (-4925 5600) $PN 12
J 0
(-4915 5610);
DISPLAY 0.489362 (-4915 5610);
PAINT MONO (-4915 5610);
FORCEPROP 0 LASTPIN (-4925 5550) $PN 11
J 0
(-4915 5560);
DISPLAY 0.489362 (-4915 5560);
PAINT MONO (-4915 5560);
FORCEPROP 0 LASTPIN (-5725 5400) $PN 1
J 2
(-5735 5410);
DISPLAY 0.489362 (-5735 5410);
PAINT MONO (-5735 5410);
FORCEPROP 0 LASTPIN (-5725 5350) $PN 2
J 2
(-5735 5360);
DISPLAY 0.489362 (-5735 5360);
PAINT MONO (-5735 5360);
FORCEPROP 0 LASTPIN (-5725 5300) $PN 7
J 2
(-5735 5310);
DISPLAY 0.489362 (-5735 5310);
PAINT MONO (-5735 5310);
FORCEPROP 0 LASTPIN (-5725 5250) $PN 8
J 2
(-5735 5260);
DISPLAY 0.489362 (-5735 5260);
PAINT MONO (-5735 5260);
FORCEPROP 0 LASTPIN (-4925 5150) $PN 10
J 0
(-4915 5160);
DISPLAY 0.489362 (-4915 5160);
PAINT MONO (-4915 5160);
FORCEPROP 0 LASTPIN (-5725 5200) $PN 9
J 2
(-5735 5210);
DISPLAY 0.489362 (-5735 5210);
PAINT MONO (-5735 5210);
FORCEPROP 0 LASTPIN (-5725 5900) $PN 16
J 2
(-5735 5910);
DISPLAY 0.489362 (-5735 5910);
PAINT MONO (-5735 5910);
FORCEPROP 0 LASTPIN (-4925 5900) $PN 15
J 0
(-4915 5910);
DISPLAY 0.489362 (-4915 5910);
PAINT MONO (-4915 5910);
FORCEPROP 2 LAST PART_TYPE SMLF
J 0
(-5575 6250);
PAINT MONO (-5575 6250);
FORCEPROP 1 LAST MATERIAL IC
J 0
(-5572 6003);
DISPLAY 0.489362 (-5572 6003);
PAINT SKYBLUE (-5572 6003);
FORCEPROP 2 LAST VALUE SN74AVC4T774PWR
J 0
(-5575 6175);
DISPLAY 0.489362 (-5575 6175);
PAINT SKYBLUE (-5575 6175);
FORCEPROP 1 LAST PART_NUMBER AL04T774K00
J 0
(-5572 6058);
DISPLAY 0.489362 (-5572 6058);
PAINT SKYBLUE (-5572 6058);
FORCEPROP 1 LAST NEEDS_NO_SIZE TRUE
J 0
(-5325 5550);
DISPLAY 0.723404 (-5325 5550);
PAINT GREEN (-5325 5550);
DISPLAY INVISIBLE (-5325 5550);
FORCEPROP 1 LAST CDS_LMAN_SYM_OUTLINE -250,450,250,-450
J 0
(-5325 5550);
DISPLAY 0.468085 (-5325 5550);
PAINT GREEN (-5325 5550);
DISPLAY INVISIBLE (-5325 5550);
FORCEPROP 2 LAST CDS_LIB pure_quanta
J 0
(-5325 5550);
DISPLAY INVISIBLE (-5325 5550);
FORCEPROP 1 LAST PATH I8
J 0
(-5325 5550);
DISPLAY 0.723404 (-5325 5550);
PAINT GREEN (-5325 5550);
DISPLAY INVISIBLE (-5325 5550);
FORCEADD OFFPAGE..1
(-7625 5700);
FORCEPROP 2 LAST $XR0 149 
J 0
(-7877 5700);
DISPLAY 0.638298 (-7877 5700);
PAINT MONO (-7877 5700);
FORCEPROP 2 LAST CDS_LIB standard
J 2
(-7625 5700);
DISPLAY INVISIBLE (-7625 5700);
FORCEPROP 1 LAST OFFPAGE TRUE
J 0
(-7300 5575);
DISPLAY 0.872340 (-7300 5575);
PAINT GREEN (-7300 5575);
DISPLAY INVISIBLE (-7300 5575);
FORCEPROP 1 LAST COMMENT_BODY TRUE
J 0
(-7500 5600);
DISPLAY 0.872340 (-7500 5600);
PAINT GREEN (-7500 5600);
DISPLAY INVISIBLE (-7500 5600);
FORCEPROP 2 LAST PATH I9
J 2
(-7800 5775);
DISPLAY 1.021277 (-7800 5775);
DISPLAY INVISIBLE (-7800 5775);
FORCEADD QUANTA_TITLE_BLOCK_C..1
(0 0);
FORCEPROP 0 LAST CDS_CON_LAST_MODIFIED Fri Mar 11 14:53:17 2022
J 0
(-1885 15);
DISPLAY INVISIBLE (-1885 15);
FORCEPROP 1 LAST CUSTOM_TXT_CDS <CON_LAST_MODIFIED>
J 0
(-1885 15);
DISPLAY 0.978723 (-1885 15);
FORCEPROP 2 LAST CUSTOM_TXT_CDS <XR_PAGE_TITLE>
J 0
(-7890 5250);
DISPLAY 0.638298 (-7890 5250);
PAINT PINK (-7890 5250);
DISPLAY INVISIBLE (-7890 5250);
FORCEPROP 1 LAST CUSTOM_TXT_CDS <NAME_2>
J 0
(-3175 50);
FORCEPROP 1 LAST CUSTOM_TXT_CDS <NAME_1>
J 0
(-3175 175);
FORCEPROP 1 LAST CUSTOM_TXT_CDS <Q_NUMBER>
J 0
(-1403 103);
DISPLAY 1.212766 (-1403 103);
FORCEPROP 1 LAST CUSTOM_TXT_CDS <Q_PROJ>
J 0
(-2382 102);
DISPLAY 1.212766 (-2382 102);
FORCEPROP 1 LAST CUSTOM_TXT_CDS <Q_REV>
J 0
(-184 103);
DISPLAY 1.212766 (-184 103);
FORCEPROP 1 LAST CUSTOM_TXT_CDS <CON_PAGE_NUM> OF <CON_TOTAL_PAGES>
J 0
(-446 18);
DISPLAY 0.978723 (-446 18);
FORCEPROP 1 LAST Q_DEPT BU9
J 1
(-3763 49);
DISPLAY 1.957447 (-3763 49);
PAINT GREEN (-3763 49);
FORCEPROP 1 LAST Q_TITLE JTAG - BUFFER
J 0
(-9225 100);
DISPLAY 2.446809 (-9225 100);
PAINT GREEN (-9225 100);
FORCEPROP 1 LAST CDS_LMAN_SYM_OUTLINE -9475,6775,100,-125
J 0
(0 0);
DISPLAY 0.468085 (0 0);
PAINT GREEN (0 0);
DISPLAY INVISIBLE (0 0);
FORCEPROP 2 LAST CDS_LIB pure_quanta
J 0
(0 0);
DISPLAY INVISIBLE (0 0);
FORCEPROP 2 LAST PAGE_BORDER TRUE
J 0
(-7890 5250);
DISPLAY 0.638298 (-7890 5250);
PAINT PINK (-7890 5250);
DISPLAY INVISIBLE (-7890 5250);
FORCEPROP 1 LAST COMMENT_BODY TRUE
J 0
(12 -13);
DISPLAY 0.978723 (12 -13);
PAINT GREEN (12 -13);
DISPLAY INVISIBLE (12 -13);
FORCEPROP 2 LAST CDS_XR_PAGE_TITLE CR-150 : @T6G_MB_LIB.T6G(SCH_1):PAGE150
J 0
(-7890 5250);
DISPLAY 0.638298 (-7890 5250);
PAINT PINK (-7890 5250);
DISPLAY INVISIBLE (-7890 5250);
WIRE 16 -1 (-4650 6000)(-4650 5925);
WIRE 16 -1 (-6050 6000)(-6050 5975);
WIRE 16 -1 (-4650 4300)(-4650 4225);
WIRE 16 -1 (-6050 4350)(-6050 4275);
WIRE 16 -1 (-4650 2600)(-4650 2525);
WIRE 16 -1 (-6225 2600)(-6225 2525);
WIRE 16 -1 (-6600 1575)(-6600 1700);
WIRE 16 -1 (-6225 2800)(-6225 2850);
WIRE 16 -1 (-6025 2850)(-6225 2850);
WIRE 16 -1 (-6025 2850)(-6025 2925);
WIRE 16 -1 (-6025 2250)(-6025 2850);
WIRE 16 -1 (-5725 2250)(-6025 2250);
WIRE 16 -1 (-6600 1900)(-6600 2000);
WIRE 16 -1 (-5725 2000)(-6600 2000);
FORCEPROP 2 LAST SIG_NAME U152_OE_N
J 0
(-6560 2010);
DISPLAY 0.489362 (-6560 2010);
FORCEPROP 2 LASTPROP $XRERR UNIQUE?
J 0
(-6800 2010);
DISPLAY 0.638298 (-6800 2010);
PAINT MONO (-6800 2010);
DISPLAY INVISIBLE (-6800 2010);
WIRE 16 -1 (-6650 2300)(-5725 2300);
FORCEPROP 2 LAST SIG_NAME JTAG_TDI
J 2
(-6410 2310);
DISPLAY 0.489362 (-6410 2310);
WIRE 16 -1 (-6650 2150)(-5725 2150);
FORCEPROP 2 LAST SIG_NAME JTAG_TDO
J 0
(-6585 2160);
DISPLAY 0.489362 (-6585 2160);
WIRE 16 -1 (-6275 3525)(-5725 3525);
FORCEPROP 2 LAST SIG_NAME CPU1_JTAG_BUF_OE
J 0
(-6210 3535);
DISPLAY 0.489362 (-6210 3535);
WIRE 16 -1 (-6025 2100)(-6025 1850);
WIRE 16 -1 (-5725 2100)(-6025 2100);
WIRE 16 -1 (-6025 1850)(-5725 1850);
WIRE 16 -1 (-6025 1850)(-6025 1800);
WIRE 16 -1 (-5725 3575)(-5850 3575);
WIRE 16 -1 (-5850 3625)(-5850 3575);
WIRE 16 -1 (-5725 3625)(-5850 3625);
WIRE 16 -1 (-5850 3675)(-5850 3625);
WIRE 16 -1 (-5725 3675)(-5850 3675);
WIRE 16 -1 (-5850 3725)(-5850 3675);
WIRE 16 -1 (-5850 3725)(-5850 4225);
WIRE 16 -1 (-5725 3725)(-5850 3725);
WIRE 16 -1 (-5725 4225)(-5850 4225);
WIRE 16 -1 (-5850 4225)(-5850 4600);
WIRE 16 -1 (-5850 4675)(-5850 4600);
WIRE 16 -1 (-5850 4600)(-6050 4600);
WIRE 16 -1 (-6050 4550)(-6050 4600);
WIRE 16 -1 (-4925 2450)(-4775 2450);
WIRE 16 -1 (-4775 2450)(-4775 2500);
WIRE 16 -1 (-4925 2500)(-4775 2500);
WIRE 16 -1 (-4775 2875)(-4775 2500);
WIRE 16 -1 (-4650 2875)(-4775 2875);
WIRE 16 -1 (-4775 2925)(-4775 2875);
WIRE 16 -1 (-4650 2800)(-4650 2875);
WIRE 16 -1 (-4800 3400)(-4800 3475);
WIRE 16 -1 (-4925 3475)(-4800 3475);
WIRE 16 -1 (-6650 4025)(-6650 5700);
WIRE 16 -1 (-6650 4025)(-5725 4025);
WIRE 16 -1 (-6650 5700)(-5725 5700);
WIRE 16 -1 (-7575 5700)(-6650 5700);
FORCEPROP 2 LAST SIG_NAME JTAG_TCK
J 0
(-7510 5710);
DISPLAY 0.489362 (-7510 5710);
WIRE 16 -1 (-5725 3975)(-6700 3975);
WIRE 16 -1 (-6700 5650)(-6700 3975);
WIRE 16 -1 (-5725 5650)(-6700 5650);
WIRE 16 -1 (-6700 5650)(-7575 5650);
FORCEPROP 2 LAST SIG_NAME JTAG_TMS
J 0
(-7510 5660);
DISPLAY 0.489362 (-7510 5660);
WIRE 16 -1 (-5725 3925)(-6750 3925);
WIRE 16 -1 (-6750 5600)(-6750 3925);
WIRE 16 -1 (-6750 5600)(-5725 5600);
WIRE 16 -1 (-7575 5600)(-6750 5600);
FORCEPROP 2 LAST SIG_NAME JTAG_TRST_N
J 0
(-7510 5610);
DISPLAY 0.489362 (-7510 5610);
WIRE 16 -1 (-5725 3875)(-6800 3875);
WIRE 16 -1 (-6800 5550)(-6800 3875);
WIRE 16 -1 (-6800 5550)(-5725 5550);
WIRE 16 -1 (-7575 5550)(-6800 5550);
FORCEPROP 2 LAST SIG_NAME JTAG_DBREQ_N
J 0
(-7510 5560);
DISPLAY 0.489362 (-7510 5560);
WIRE 16 -1 (-6275 5200)(-5725 5200);
FORCEPROP 2 LAST SIG_NAME CPU0_JTAG_BUF_OE
J 0
(-6210 5210);
DISPLAY 0.489362 (-6210 5210);
WIRE 16 -1 (-5725 5250)(-5850 5250);
WIRE 16 -1 (-5850 5300)(-5850 5250);
WIRE 16 -1 (-5725 5300)(-5850 5300);
WIRE 16 -1 (-5850 5350)(-5850 5300);
WIRE 16 -1 (-5850 5400)(-5850 5350);
WIRE 16 -1 (-5725 5350)(-5850 5350);
WIRE 16 -1 (-5850 5400)(-5850 5900);
WIRE 16 -1 (-5725 5400)(-5850 5400);
WIRE 16 -1 (-5850 5900)(-5850 6300);
WIRE 16 -1 (-5725 5900)(-5850 5900);
WIRE 16 -1 (-5850 6375)(-5850 6300);
WIRE 16 -1 (-5850 6300)(-6050 6300);
WIRE 16 -1 (-6050 6200)(-6050 6300);
WIRE 16 -1 (-4925 4225)(-4800 4225);
WIRE 16 -1 (-4800 4225)(-4800 4575);
WIRE 16 -1 (-4800 4675)(-4800 4575);
WIRE 16 -1 (-4650 4575)(-4800 4575);
WIRE 16 -1 (-4650 4500)(-4650 4575);
WIRE 16 -1 (-4800 5025)(-4800 5150);
WIRE 16 -1 (-4925 5150)(-4800 5150);
WIRE 16 -1 (-4925 5900)(-4800 5900);
WIRE 16 -1 (-4800 5900)(-4800 6275);
WIRE 16 -1 (-4800 6375)(-4800 6275);
WIRE 16 -1 (-4650 6275)(-4800 6275);
WIRE 16 -1 (-4650 6200)(-4650 6275);
WIRE 16 -1 (-3725 3975)(-4925 3975);
FORCEPROP 2 LAST SIG_NAME JTAG_P1_R_TMS
J 0
(-4685 3985);
DISPLAY 0.489362 (-4685 3985);
FORCEPROP 2 LASTPROP $XRERR UNIQUE?
J 0
(-4925 3985);
DISPLAY 0.638298 (-4925 3985);
PAINT MONO (-4925 3985);
DISPLAY INVISIBLE (-4925 3985);
WIRE 16 -1 (-4925 3925)(-3725 3925);
FORCEPROP 2 LAST SIG_NAME JTAG_P1_R_TRST_N
J 0
(-4685 3935);
DISPLAY 0.489362 (-4685 3935);
FORCEPROP 2 LASTPROP $XRERR UNIQUE?
J 0
(-4925 3935);
DISPLAY 0.638298 (-4925 3935);
PAINT MONO (-4925 3935);
DISPLAY INVISIBLE (-4925 3935);
WIRE 16 -1 (-4925 3875)(-3725 3875);
FORCEPROP 2 LAST SIG_NAME JTAG_P1_R_DBREQ_N
J 0
(-4685 3885);
DISPLAY 0.489362 (-4685 3885);
FORCEPROP 2 LASTPROP $XRERR UNIQUE?
J 0
(-4925 3885);
DISPLAY 0.638298 (-4925 3885);
PAINT MONO (-4925 3885);
DISPLAY INVISIBLE (-4925 3885);
WIRE 16 -1 (-3725 5650)(-4925 5650);
FORCEPROP 2 LAST SIG_NAME JTAG_P0_R_TMS
J 0
(-4685 5660);
DISPLAY 0.489362 (-4685 5660);
FORCEPROP 2 LASTPROP $XRERR UNIQUE?
J 0
(-4925 5660);
DISPLAY 0.638298 (-4925 5660);
PAINT MONO (-4925 5660);
DISPLAY INVISIBLE (-4925 5660);
WIRE 16 -1 (-4925 5700)(-3725 5700);
FORCEPROP 2 LAST SIG_NAME JTAG_P0_R_TCK
J 0
(-4685 5710);
DISPLAY 0.489362 (-4685 5710);
FORCEPROP 2 LASTPROP $XRERR UNIQUE?
J 0
(-4925 5710);
DISPLAY 0.638298 (-4925 5710);
PAINT MONO (-4925 5710);
DISPLAY INVISIBLE (-4925 5710);
WIRE 16 -1 (-4925 5600)(-3725 5600);
FORCEPROP 2 LAST SIG_NAME JTAG_P0_R_TRST_N
J 0
(-4685 5610);
DISPLAY 0.489362 (-4685 5610);
FORCEPROP 2 LASTPROP $XRERR UNIQUE?
J 0
(-4925 5610);
DISPLAY 0.638298 (-4925 5610);
PAINT MONO (-4925 5610);
DISPLAY INVISIBLE (-4925 5610);
WIRE 16 -1 (-4925 5550)(-3725 5550);
FORCEPROP 2 LAST SIG_NAME JTAG_P0_R_DBREQ_N
J 0
(-4685 5560);
DISPLAY 0.489362 (-4685 5560);
FORCEPROP 2 LASTPROP $XRERR UNIQUE?
J 0
(-4925 5560);
DISPLAY 0.638298 (-4925 5560);
PAINT MONO (-4925 5560);
DISPLAY INVISIBLE (-4925 5560);
WIRE 16 -1 (-4925 4025)(-3725 4025);
FORCEPROP 2 LAST SIG_NAME JTAG_P1_R_TCK
J 0
(-4685 4035);
DISPLAY 0.489362 (-4685 4035);
FORCEPROP 2 LASTPROP $XRERR UNIQUE?
J 0
(-4925 4035);
DISPLAY 0.638298 (-4925 4035);
PAINT MONO (-4925 4035);
DISPLAY INVISIBLE (-4925 4035);
WIRE 16 -1 (-4925 2250)(-4000 2250);
FORCEPROP 2 LAST SIG_NAME JTAG_CPUX_TDI
J 0
(-4660 2260);
DISPLAY 0.489362 (-4660 2260);
WIRE 16 -1 (-4925 2100)(-4000 2100);
FORCEPROP 2 LAST SIG_NAME JTAG_CPUX_TDO
J 0
(-4660 2110);
DISPLAY 0.489362 (-4660 2110);
WIRE 16 -1 (-2375 3925)(-3525 3925);
FORCEPROP 2 LAST SIG_NAME JTAG_CPU1_TRST_N
J 0
(-3335 3935);
DISPLAY 0.489362 (-3335 3935);
WIRE 16 -1 (-2375 3975)(-3525 3975);
FORCEPROP 2 LAST SIG_NAME JTAG_CPU1_TMS
J 0
(-3335 3985);
DISPLAY 0.489362 (-3335 3985);
WIRE 16 -1 (-3525 4025)(-2375 4025);
FORCEPROP 2 LAST SIG_NAME JTAG_CPU1_TCK
J 0
(-3335 4035);
DISPLAY 0.489362 (-3335 4035);
WIRE 16 -1 (-3525 3875)(-2375 3875);
FORCEPROP 2 LAST SIG_NAME JTAG_CPU1_DBREQ_N
J 0
(-3335 3885);
DISPLAY 0.489362 (-3335 3885);
WIRE 16 -1 (-2425 5700)(-3525 5700);
FORCEPROP 2 LAST SIG_NAME JTAG_CPU0_TCK
J 0
(-3360 5710);
DISPLAY 0.489362 (-3360 5710);
WIRE 16 -1 (-3525 5550)(-2425 5550);
FORCEPROP 2 LAST SIG_NAME JTAG_CPU0_DBREQ_N
J 0
(-3360 5560);
DISPLAY 0.489362 (-3360 5560);
WIRE 16 -1 (-3525 5600)(-2425 5600);
FORCEPROP 2 LAST SIG_NAME JTAG_CPU0_TRST_N
J 0
(-3360 5610);
DISPLAY 0.489362 (-3360 5610);
WIRE 16 -1 (-2425 5650)(-3525 5650);
FORCEPROP 2 LAST SIG_NAME JTAG_CPU0_TMS
J 0
(-3360 5660);
DISPLAY 0.489362 (-3360 5660);
DOT 1 (-5850 4225);
DOT 1 (-5850 5300);
DOT 1 (-5850 5350);
DOT 1 (-6800 5550);
DOT 1 (-6025 1850);
DOT 1 (-6025 2850);
DOT 1 (-5850 3625);
DOT 1 (-5850 3675);
DOT 1 (-5850 3725);
DOT 1 (-4775 2500);
DOT 1 (-4775 2875);
DOT 1 (-6750 5600);
DOT 1 (-6700 5650);
DOT 1 (-6650 5700);
DOT 1 (-5850 4600);
DOT 1 (-5850 5400);
DOT 1 (-5850 5900);
DOT 1 (-4800 4575);
DOT 1 (-5850 6300);
DOT 1 (-4800 6275);
FORCENOTE
CPU1
(-2725 4175) 0;
DISPLAY LEFT (-2725 4175);
DISPLAY 2.510638 (-2725 4175);
PAINT WHITE (-2725 4175);
FORCENOTE
CPU0
(-2775 5975) 0;
DISPLAY LEFT (-2775 5975);
DISPLAY 2.510638 (-2775 5975);
PAINT WHITE (-2775 5975);
FORCENOTE
CPU0/1 TDI/TDO DAISY CHAIN 
(-3675 2450) 0;
DISPLAY LEFT (-3675 2450);
DISPLAY 2.510638 (-3675 2450);
PAINT WHITE (-3675 2450);
QUIT
